FILE_TYPE = MACRO_DRAWING;
SET COLOR_WIRE YELLOW;
SET COLOR_PROP ORANGE;
SET COLOR_DOT WHITE;
SET COLOR_ARC YELLOW;
SET COLOR_BODY GREEN;
SET COLOR_NOTE PURPLE;
SET PROP_DISPLAY VALUE;
SET PAGE_NUMBER P21;
FORCEADD GENOA_SP5..35
(-4500 3625);
FORCEPROP 1 LAST LOCATION U25
J 0
(-5145 6456);
DISPLAY 0.489362 (-5145 6456);
PAINT SKYBLUE (-5145 6456);
FORCEPROP 0 LAST $SEC 35
J 0
(-5125 6500);
DISPLAY 0.680851 (-5125 6500);
PAINT MONO (-5125 6500);
DISPLAY INVISIBLE (-5125 6500);
FORCEPROP 0 LAST CDS_SEC 35
J 0
(-5150 6450);
DISPLAY 1.021277 (-5150 6450);
DISPLAY INVISIBLE (-5150 6450);
FORCEPROP 0 LASTPIN (-5300 3000) $PN BC9
J 2
(-5310 3010);
DISPLAY 0.489362 (-5310 3010);
PAINT MONO (-5310 3010);
FORCEPROP 0 LASTPIN (-5300 2950) $PN BD9
J 2
(-5310 2960);
DISPLAY 0.489362 (-5310 2960);
PAINT MONO (-5310 2960);
FORCEPROP 0 LASTPIN (-5300 1850) $PN BF9
J 2
(-5310 1860);
DISPLAY 0.489362 (-5310 1860);
PAINT MONO (-5310 1860);
FORCEPROP 0 LASTPIN (-5300 1800) $PN BG9
J 2
(-5310 1810);
DISPLAY 0.489362 (-5310 1810);
PAINT MONO (-5310 1810);
FORCEPROP 0 LASTPIN (-5300 2150) $PN AT11
J 2
(-5310 2160);
DISPLAY 0.489362 (-5310 2160);
PAINT MONO (-5310 2160);
FORCEPROP 0 LASTPIN (-5300 2050) $PN AU10
J 2
(-5310 2060);
DISPLAY 0.489362 (-5310 2060);
PAINT MONO (-5310 2060);
FORCEPROP 0 LASTPIN (-5300 2850) $PN AU9
J 2
(-5310 2860);
DISPLAY 0.489362 (-5310 2860);
PAINT MONO (-5310 2860);
FORCEPROP 0 LASTPIN (-5300 2800) $PN AV11
J 2
(-5310 2810);
DISPLAY 0.489362 (-5310 2810);
PAINT MONO (-5310 2810);
FORCEPROP 0 LASTPIN (-5300 2700) $PN BN10
J 2
(-5310 2710);
DISPLAY 0.489362 (-5310 2710);
PAINT MONO (-5310 2710);
FORCEPROP 0 LASTPIN (-5300 1700) $PN AV9
J 2
(-5310 1710);
DISPLAY 0.489362 (-5310 1710);
PAINT MONO (-5310 1710);
FORCEPROP 0 LASTPIN (-5300 1650) $PN AW10
J 2
(-5310 1660);
DISPLAY 0.489362 (-5310 1660);
PAINT MONO (-5310 1660);
FORCEPROP 0 LASTPIN (-5300 1550) $PN BP11
J 2
(-5310 1560);
DISPLAY 0.489362 (-5310 1560);
PAINT MONO (-5310 1560);
FORCEPROP 0 LASTPIN (-5300 3850) $PN AW9
J 2
(-5310 3860);
DISPLAY 0.489362 (-5310 3860);
PAINT MONO (-5310 3860);
FORCEPROP 0 LASTPIN (-5300 3800) $PN AY9
J 2
(-5310 3810);
DISPLAY 0.489362 (-5310 3810);
PAINT MONO (-5310 3810);
FORCEPROP 0 LASTPIN (-5300 3750) $PN AY11
J 2
(-5310 3760);
DISPLAY 0.489362 (-5310 3760);
PAINT MONO (-5310 3760);
FORCEPROP 0 LASTPIN (-5300 3700) $PN BA10
J 2
(-5310 3710);
DISPLAY 0.489362 (-5310 3710);
PAINT MONO (-5310 3710);
FORCEPROP 0 LASTPIN (-5300 3650) $PN BA9
J 2
(-5310 3660);
DISPLAY 0.489362 (-5310 3660);
PAINT MONO (-5310 3660);
FORCEPROP 0 LASTPIN (-5300 3600) $PN BB9
J 2
(-5310 3610);
DISPLAY 0.489362 (-5310 3610);
PAINT MONO (-5310 3610);
FORCEPROP 0 LASTPIN (-5300 3550) $PN BB11
J 2
(-5310 3560);
DISPLAY 0.489362 (-5310 3560);
PAINT MONO (-5310 3560);
FORCEPROP 0 LASTPIN (-3700 2400) $PN AJ9
J 0
(-3690 2410);
DISPLAY 0.489362 (-3690 2410);
PAINT MONO (-3690 2410);
FORCEPROP 0 LASTPIN (-3700 2350) $PN AK11
J 0
(-3690 2360);
DISPLAY 0.489362 (-3690 2360);
PAINT MONO (-3690 2360);
FORCEPROP 0 LASTPIN (-3700 2300) $PN AK9
J 0
(-3690 2310);
DISPLAY 0.489362 (-3690 2310);
PAINT MONO (-3690 2310);
FORCEPROP 0 LASTPIN (-3700 2250) $PN AL10
J 0
(-3690 2260);
DISPLAY 0.489362 (-3690 2260);
PAINT MONO (-3690 2260);
FORCEPROP 0 LASTPIN (-3700 2200) $PN AN9
J 0
(-3690 2210);
DISPLAY 0.489362 (-3690 2210);
PAINT MONO (-3690 2210);
FORCEPROP 0 LASTPIN (-3700 2150) $PN AP11
J 0
(-3690 2160);
DISPLAY 0.489362 (-3690 2160);
PAINT MONO (-3690 2160);
FORCEPROP 0 LASTPIN (-3700 2100) $PN AP9
J 0
(-3690 2110);
DISPLAY 0.489362 (-3690 2110);
PAINT MONO (-3690 2110);
FORCEPROP 0 LASTPIN (-3700 2050) $PN AR10
J 0
(-3690 2060);
DISPLAY 0.489362 (-3690 2060);
PAINT MONO (-3690 2060);
FORCEPROP 0 LASTPIN (-3700 6000) $PN E9
J 0
(-3690 6010);
DISPLAY 0.489362 (-3690 6010);
PAINT MONO (-3690 6010);
FORCEPROP 0 LASTPIN (-3700 5950) $PN F11
J 0
(-3690 5960);
DISPLAY 0.489362 (-3690 5960);
PAINT MONO (-3690 5960);
FORCEPROP 0 LASTPIN (-3700 5900) $PN F9
J 0
(-3690 5910);
DISPLAY 0.489362 (-3690 5910);
PAINT MONO (-3690 5910);
FORCEPROP 0 LASTPIN (-3700 5850) $PN G10
J 0
(-3690 5860);
DISPLAY 0.489362 (-3690 5860);
PAINT MONO (-3690 5860);
FORCEPROP 0 LASTPIN (-3700 5800) $PN J9
J 0
(-3690 5810);
DISPLAY 0.489362 (-3690 5810);
PAINT MONO (-3690 5810);
FORCEPROP 0 LASTPIN (-3700 5750) $PN K11
J 0
(-3690 5760);
DISPLAY 0.489362 (-3690 5760);
PAINT MONO (-3690 5760);
FORCEPROP 0 LASTPIN (-3700 5700) $PN K9
J 0
(-3690 5710);
DISPLAY 0.489362 (-3690 5710);
PAINT MONO (-3690 5710);
FORCEPROP 0 LASTPIN (-3700 5650) $PN L10
J 0
(-3690 5660);
DISPLAY 0.489362 (-3690 5660);
PAINT MONO (-3690 5660);
FORCEPROP 0 LASTPIN (-3700 5550) $PN L9
J 0
(-3690 5560);
DISPLAY 0.489362 (-3690 5560);
PAINT MONO (-3690 5560);
FORCEPROP 0 LASTPIN (-3700 5500) $PN M11
J 0
(-3690 5510);
DISPLAY 0.489362 (-3690 5510);
PAINT MONO (-3690 5510);
FORCEPROP 0 LASTPIN (-3700 5450) $PN M9
J 0
(-3690 5460);
DISPLAY 0.489362 (-3690 5460);
PAINT MONO (-3690 5460);
FORCEPROP 0 LASTPIN (-3700 5400) $PN N10
J 0
(-3690 5410);
DISPLAY 0.489362 (-3690 5410);
PAINT MONO (-3690 5410);
FORCEPROP 0 LASTPIN (-3700 5350) $PN R9
J 0
(-3690 5360);
DISPLAY 0.489362 (-3690 5360);
PAINT MONO (-3690 5360);
FORCEPROP 0 LASTPIN (-3700 5300) $PN T11
J 0
(-3690 5310);
DISPLAY 0.489362 (-3690 5310);
PAINT MONO (-3690 5310);
FORCEPROP 0 LASTPIN (-3700 5250) $PN T9
J 0
(-3690 5260);
DISPLAY 0.489362 (-3690 5260);
PAINT MONO (-3690 5260);
FORCEPROP 0 LASTPIN (-3700 5200) $PN U10
J 0
(-3690 5210);
DISPLAY 0.489362 (-3690 5210);
PAINT MONO (-3690 5210);
FORCEPROP 0 LASTPIN (-3700 5100) $PN U9
J 0
(-3690 5110);
DISPLAY 0.489362 (-3690 5110);
PAINT MONO (-3690 5110);
FORCEPROP 0 LASTPIN (-3700 5050) $PN V11
J 0
(-3690 5060);
DISPLAY 0.489362 (-3690 5060);
PAINT MONO (-3690 5060);
FORCEPROP 0 LASTPIN (-3700 5000) $PN V9
J 0
(-3690 5010);
DISPLAY 0.489362 (-3690 5010);
PAINT MONO (-3690 5010);
FORCEPROP 0 LASTPIN (-3700 4950) $PN W10
J 0
(-3690 4960);
DISPLAY 0.489362 (-3690 4960);
PAINT MONO (-3690 4960);
FORCEPROP 0 LASTPIN (-3700 4900) $PN AA9
J 0
(-3690 4910);
DISPLAY 0.489362 (-3690 4910);
PAINT MONO (-3690 4910);
FORCEPROP 0 LASTPIN (-3700 4850) $PN AB11
J 0
(-3690 4860);
DISPLAY 0.489362 (-3690 4860);
PAINT MONO (-3690 4860);
FORCEPROP 0 LASTPIN (-3700 4800) $PN AB9
J 0
(-3690 4810);
DISPLAY 0.489362 (-3690 4810);
PAINT MONO (-3690 4810);
FORCEPROP 0 LASTPIN (-3700 4750) $PN AC10
J 0
(-3690 4760);
DISPLAY 0.489362 (-3690 4760);
PAINT MONO (-3690 4760);
FORCEPROP 0 LASTPIN (-3700 4650) $PN AC9
J 0
(-3690 4660);
DISPLAY 0.489362 (-3690 4660);
PAINT MONO (-3690 4660);
FORCEPROP 0 LASTPIN (-3700 4600) $PN AD11
J 0
(-3690 4610);
DISPLAY 0.489362 (-3690 4610);
PAINT MONO (-3690 4610);
FORCEPROP 0 LASTPIN (-3700 4550) $PN AD9
J 0
(-3690 4560);
DISPLAY 0.489362 (-3690 4560);
PAINT MONO (-3690 4560);
FORCEPROP 0 LASTPIN (-3700 4500) $PN AE10
J 0
(-3690 4510);
DISPLAY 0.489362 (-3690 4510);
PAINT MONO (-3690 4510);
FORCEPROP 0 LASTPIN (-3700 4450) $PN AG9
J 0
(-3690 4460);
DISPLAY 0.489362 (-3690 4460);
PAINT MONO (-3690 4460);
FORCEPROP 0 LASTPIN (-3700 4400) $PN AH11
J 0
(-3690 4410);
DISPLAY 0.489362 (-3690 4410);
PAINT MONO (-3690 4410);
FORCEPROP 0 LASTPIN (-3700 4350) $PN AH9
J 0
(-3690 4360);
DISPLAY 0.489362 (-3690 4360);
PAINT MONO (-3690 4360);
FORCEPROP 0 LASTPIN (-3700 4300) $PN AJ10
J 0
(-3690 4310);
DISPLAY 0.489362 (-3690 4310);
PAINT MONO (-3690 4310);
FORCEPROP 0 LASTPIN (-5300 6000) $PN G9
J 2
(-5310 6010);
DISPLAY 0.489362 (-5310 6010);
PAINT MONO (-5310 6010);
FORCEPROP 0 LASTPIN (-5300 5900) $PN N9
J 2
(-5310 5910);
DISPLAY 0.489362 (-5310 5910);
PAINT MONO (-5310 5910);
FORCEPROP 0 LASTPIN (-5300 5800) $PN W9
J 2
(-5310 5810);
DISPLAY 0.489362 (-5310 5810);
PAINT MONO (-5310 5810);
FORCEPROP 0 LASTPIN (-5300 5700) $PN AE9
J 2
(-5310 5710);
DISPLAY 0.489362 (-5310 5710);
PAINT MONO (-5310 5710);
FORCEPROP 0 LASTPIN (-5300 5600) $PN AL9
J 2
(-5310 5610);
DISPLAY 0.489362 (-5310 5610);
PAINT MONO (-5310 5610);
FORCEPROP 0 LASTPIN (-5300 5500) $PN J10
J 2
(-5310 5510);
DISPLAY 0.489362 (-5310 5510);
PAINT MONO (-5310 5510);
FORCEPROP 0 LASTPIN (-5300 5400) $PN R10
J 2
(-5310 5410);
DISPLAY 0.489362 (-5310 5410);
PAINT MONO (-5310 5410);
FORCEPROP 0 LASTPIN (-5300 5300) $PN AA10
J 2
(-5310 5310);
DISPLAY 0.489362 (-5310 5310);
PAINT MONO (-5310 5310);
FORCEPROP 0 LASTPIN (-5300 5200) $PN AG10
J 2
(-5310 5210);
DISPLAY 0.489362 (-5310 5210);
PAINT MONO (-5310 5210);
FORCEPROP 0 LASTPIN (-5300 5100) $PN AN10
J 2
(-5310 5110);
DISPLAY 0.489362 (-5310 5110);
PAINT MONO (-5310 5110);
FORCEPROP 0 LASTPIN (-5300 5950) $PN H9
J 2
(-5310 5960);
DISPLAY 0.489362 (-5310 5960);
PAINT MONO (-5310 5960);
FORCEPROP 0 LASTPIN (-5300 5850) $PN P9
J 2
(-5310 5860);
DISPLAY 0.489362 (-5310 5860);
PAINT MONO (-5310 5860);
FORCEPROP 0 LASTPIN (-5300 5750) $PN Y9
J 2
(-5310 5760);
DISPLAY 0.489362 (-5310 5760);
PAINT MONO (-5310 5760);
FORCEPROP 0 LASTPIN (-5300 5650) $PN AF9
J 2
(-5310 5660);
DISPLAY 0.489362 (-5310 5660);
PAINT MONO (-5310 5660);
FORCEPROP 0 LASTPIN (-5300 5550) $PN AM9
J 2
(-5310 5560);
DISPLAY 0.489362 (-5310 5560);
PAINT MONO (-5310 5560);
FORCEPROP 0 LASTPIN (-5300 5450) $PN H11
J 2
(-5310 5460);
DISPLAY 0.489362 (-5310 5460);
PAINT MONO (-5310 5460);
FORCEPROP 0 LASTPIN (-5300 5350) $PN P11
J 2
(-5310 5360);
DISPLAY 0.489362 (-5310 5360);
PAINT MONO (-5310 5360);
FORCEPROP 0 LASTPIN (-5300 5250) $PN Y11
J 2
(-5310 5260);
DISPLAY 0.489362 (-5310 5260);
PAINT MONO (-5310 5260);
FORCEPROP 0 LASTPIN (-5300 5150) $PN AF11
J 2
(-5310 5160);
DISPLAY 0.489362 (-5310 5160);
PAINT MONO (-5310 5160);
FORCEPROP 0 LASTPIN (-5300 5050) $PN AM11
J 2
(-5310 5060);
DISPLAY 0.489362 (-5310 5060);
PAINT MONO (-5310 5060);
FORCEPROP 0 LASTPIN (-5300 2600) $PN BC10
J 2
(-5310 2610);
DISPLAY 0.489362 (-5310 2610);
PAINT MONO (-5310 2610);
FORCEPROP 0 LASTPIN (-5300 2500) $PN BM11
J 2
(-5310 2510);
DISPLAY 0.489362 (-5310 2510);
PAINT MONO (-5310 2510);
FORCEPROP 0 LASTPIN (-5300 2450) $PN BN9
J 2
(-5310 2460);
DISPLAY 0.489362 (-5310 2460);
PAINT MONO (-5310 2460);
FORCEPROP 0 LASTPIN (-5300 2350) $PN BP9
J 2
(-5310 2360);
DISPLAY 0.489362 (-5310 2360);
PAINT MONO (-5310 2360);
FORCEPROP 0 LASTPIN (-5300 1450) $PN BL9
J 2
(-5310 1460);
DISPLAY 0.489362 (-5310 1460);
PAINT MONO (-5310 1460);
FORCEPROP 0 LASTPIN (-5300 1400) $PN BM9
J 2
(-5310 1410);
DISPLAY 0.489362 (-5310 1410);
PAINT MONO (-5310 1410);
FORCEPROP 0 LASTPIN (-5300 1300) $PN BR9
J 2
(-5310 1310);
DISPLAY 0.489362 (-5310 1310);
PAINT MONO (-5310 1310);
FORCEPROP 0 LASTPIN (-5300 3450) $PN BG10
J 2
(-5310 3460);
DISPLAY 0.489362 (-5310 3460);
PAINT MONO (-5310 3460);
FORCEPROP 0 LASTPIN (-5300 3400) $PN BH11
J 2
(-5310 3410);
DISPLAY 0.489362 (-5310 3410);
PAINT MONO (-5310 3410);
FORCEPROP 0 LASTPIN (-5300 3350) $PN BH9
J 2
(-5310 3360);
DISPLAY 0.489362 (-5310 3360);
PAINT MONO (-5310 3360);
FORCEPROP 0 LASTPIN (-5300 3300) $PN BJ9
J 2
(-5310 3310);
DISPLAY 0.489362 (-5310 3310);
PAINT MONO (-5310 3310);
FORCEPROP 0 LASTPIN (-5300 3250) $PN BJ10
J 2
(-5310 3260);
DISPLAY 0.489362 (-5310 3260);
PAINT MONO (-5310 3260);
FORCEPROP 0 LASTPIN (-5300 3200) $PN BK11
J 2
(-5310 3210);
DISPLAY 0.489362 (-5310 3210);
PAINT MONO (-5310 3210);
FORCEPROP 0 LASTPIN (-5300 3150) $PN BK9
J 2
(-5310 3160);
DISPLAY 0.489362 (-5310 3160);
PAINT MONO (-5310 3160);
FORCEPROP 0 LASTPIN (-3700 1950) $PN BY9
J 0
(-3690 1960);
DISPLAY 0.489362 (-3690 1960);
PAINT MONO (-3690 1960);
FORCEPROP 0 LASTPIN (-3700 1900) $PN CA10
J 0
(-3690 1910);
DISPLAY 0.489362 (-3690 1910);
PAINT MONO (-3690 1910);
FORCEPROP 0 LASTPIN (-3700 1850) $PN CA9
J 0
(-3690 1860);
DISPLAY 0.489362 (-3690 1860);
PAINT MONO (-3690 1860);
FORCEPROP 0 LASTPIN (-3700 1800) $PN CB11
J 0
(-3690 1810);
DISPLAY 0.489362 (-3690 1810);
PAINT MONO (-3690 1810);
FORCEPROP 0 LASTPIN (-3700 1750) $PN BT9
J 0
(-3690 1760);
DISPLAY 0.489362 (-3690 1760);
PAINT MONO (-3690 1760);
FORCEPROP 0 LASTPIN (-3700 1700) $PN BU10
J 0
(-3690 1710);
DISPLAY 0.489362 (-3690 1710);
PAINT MONO (-3690 1710);
FORCEPROP 0 LASTPIN (-3700 1650) $PN BU9
J 0
(-3690 1660);
DISPLAY 0.489362 (-3690 1660);
PAINT MONO (-3690 1660);
FORCEPROP 0 LASTPIN (-3700 1600) $PN BV11
J 0
(-3690 1610);
DISPLAY 0.489362 (-3690 1610);
PAINT MONO (-3690 1610);
FORCEPROP 0 LASTPIN (-3700 4200) $PN CB9
J 0
(-3690 4210);
DISPLAY 0.489362 (-3690 4210);
PAINT MONO (-3690 4210);
FORCEPROP 0 LASTPIN (-3700 4150) $PN CC10
J 0
(-3690 4160);
DISPLAY 0.489362 (-3690 4160);
PAINT MONO (-3690 4160);
FORCEPROP 0 LASTPIN (-3700 4100) $PN CC9
J 0
(-3690 4110);
DISPLAY 0.489362 (-3690 4110);
PAINT MONO (-3690 4110);
FORCEPROP 0 LASTPIN (-3700 4050) $PN CD11
J 0
(-3690 4060);
DISPLAY 0.489362 (-3690 4060);
PAINT MONO (-3690 4060);
FORCEPROP 0 LASTPIN (-3700 4000) $PN CF9
J 0
(-3690 4010);
DISPLAY 0.489362 (-3690 4010);
PAINT MONO (-3690 4010);
FORCEPROP 0 LASTPIN (-3700 3950) $PN CG10
J 0
(-3690 3960);
DISPLAY 0.489362 (-3690 3960);
PAINT MONO (-3690 3960);
FORCEPROP 0 LASTPIN (-3700 3900) $PN CG9
J 0
(-3690 3910);
DISPLAY 0.489362 (-3690 3910);
PAINT MONO (-3690 3910);
FORCEPROP 0 LASTPIN (-3700 3850) $PN CH11
J 0
(-3690 3860);
DISPLAY 0.489362 (-3690 3860);
PAINT MONO (-3690 3860);
FORCEPROP 0 LASTPIN (-3700 3750) $PN CH9
J 0
(-3690 3760);
DISPLAY 0.489362 (-3690 3760);
PAINT MONO (-3690 3760);
FORCEPROP 0 LASTPIN (-3700 3700) $PN CJ10
J 0
(-3690 3710);
DISPLAY 0.489362 (-3690 3710);
PAINT MONO (-3690 3710);
FORCEPROP 0 LASTPIN (-3700 3650) $PN CJ9
J 0
(-3690 3660);
DISPLAY 0.489362 (-3690 3660);
PAINT MONO (-3690 3660);
FORCEPROP 0 LASTPIN (-3700 3600) $PN CK11
J 0
(-3690 3610);
DISPLAY 0.489362 (-3690 3610);
PAINT MONO (-3690 3610);
FORCEPROP 0 LASTPIN (-3700 3550) $PN CM9
J 0
(-3690 3560);
DISPLAY 0.489362 (-3690 3560);
PAINT MONO (-3690 3560);
FORCEPROP 0 LASTPIN (-3700 3500) $PN CN10
J 0
(-3690 3510);
DISPLAY 0.489362 (-3690 3510);
PAINT MONO (-3690 3510);
FORCEPROP 0 LASTPIN (-3700 3450) $PN CN9
J 0
(-3690 3460);
DISPLAY 0.489362 (-3690 3460);
PAINT MONO (-3690 3460);
FORCEPROP 0 LASTPIN (-3700 3400) $PN CP11
J 0
(-3690 3410);
DISPLAY 0.489362 (-3690 3410);
PAINT MONO (-3690 3410);
FORCEPROP 0 LASTPIN (-3700 3300) $PN CP9
J 0
(-3690 3310);
DISPLAY 0.489362 (-3690 3310);
PAINT MONO (-3690 3310);
FORCEPROP 0 LASTPIN (-3700 3250) $PN CR10
J 0
(-3690 3260);
DISPLAY 0.489362 (-3690 3260);
PAINT MONO (-3690 3260);
FORCEPROP 0 LASTPIN (-3700 3200) $PN CR9
J 0
(-3690 3210);
DISPLAY 0.489362 (-3690 3210);
PAINT MONO (-3690 3210);
FORCEPROP 0 LASTPIN (-3700 3150) $PN CT11
J 0
(-3690 3160);
DISPLAY 0.489362 (-3690 3160);
PAINT MONO (-3690 3160);
FORCEPROP 0 LASTPIN (-3700 3100) $PN CV9
J 0
(-3690 3110);
DISPLAY 0.489362 (-3690 3110);
PAINT MONO (-3690 3110);
FORCEPROP 0 LASTPIN (-3700 3050) $PN CW10
J 0
(-3690 3060);
DISPLAY 0.489362 (-3690 3060);
PAINT MONO (-3690 3060);
FORCEPROP 0 LASTPIN (-3700 3000) $PN CW9
J 0
(-3690 3010);
DISPLAY 0.489362 (-3690 3010);
PAINT MONO (-3690 3010);
FORCEPROP 0 LASTPIN (-3700 2950) $PN CY11
J 0
(-3690 2960);
DISPLAY 0.489362 (-3690 2960);
PAINT MONO (-3690 2960);
FORCEPROP 0 LASTPIN (-3700 2850) $PN CY9
J 0
(-3690 2860);
DISPLAY 0.489362 (-3690 2860);
PAINT MONO (-3690 2860);
FORCEPROP 0 LASTPIN (-3700 2800) $PN DA10
J 0
(-3690 2810);
DISPLAY 0.489362 (-3690 2810);
PAINT MONO (-3690 2810);
FORCEPROP 0 LASTPIN (-3700 2750) $PN DA9
J 0
(-3690 2760);
DISPLAY 0.489362 (-3690 2760);
PAINT MONO (-3690 2760);
FORCEPROP 0 LASTPIN (-3700 2700) $PN DB11
J 0
(-3690 2710);
DISPLAY 0.489362 (-3690 2710);
PAINT MONO (-3690 2710);
FORCEPROP 0 LASTPIN (-3700 2650) $PN DD9
J 0
(-3690 2660);
DISPLAY 0.489362 (-3690 2660);
PAINT MONO (-3690 2660);
FORCEPROP 0 LASTPIN (-3700 2600) $PN DE10
J 0
(-3690 2610);
DISPLAY 0.489362 (-3690 2610);
PAINT MONO (-3690 2610);
FORCEPROP 0 LASTPIN (-3700 2550) $PN DE9
J 0
(-3690 2560);
DISPLAY 0.489362 (-3690 2560);
PAINT MONO (-3690 2560);
FORCEPROP 0 LASTPIN (-3700 2500) $PN DF9
J 0
(-3690 2510);
DISPLAY 0.489362 (-3690 2510);
PAINT MONO (-3690 2510);
FORCEPROP 0 LASTPIN (-5300 4950) $PN CD9
J 2
(-5310 4960);
DISPLAY 0.489362 (-5310 4960);
PAINT MONO (-5310 4960);
FORCEPROP 0 LASTPIN (-5300 4850) $PN CK9
J 2
(-5310 4860);
DISPLAY 0.489362 (-5310 4860);
PAINT MONO (-5310 4860);
FORCEPROP 0 LASTPIN (-5300 4750) $PN CT9
J 2
(-5310 4760);
DISPLAY 0.489362 (-5310 4760);
PAINT MONO (-5310 4760);
FORCEPROP 0 LASTPIN (-5300 4650) $PN DB9
J 2
(-5310 4660);
DISPLAY 0.489362 (-5310 4660);
PAINT MONO (-5310 4660);
FORCEPROP 0 LASTPIN (-5300 4550) $PN BY11
J 2
(-5310 4560);
DISPLAY 0.489362 (-5310 4560);
PAINT MONO (-5310 4560);
FORCEPROP 0 LASTPIN (-5300 4450) $PN CF11
J 2
(-5310 4460);
DISPLAY 0.489362 (-5310 4460);
PAINT MONO (-5310 4460);
FORCEPROP 0 LASTPIN (-5300 4350) $PN CM11
J 2
(-5310 4360);
DISPLAY 0.489362 (-5310 4360);
PAINT MONO (-5310 4360);
FORCEPROP 0 LASTPIN (-5300 4250) $PN CV11
J 2
(-5310 4260);
DISPLAY 0.489362 (-5310 4260);
PAINT MONO (-5310 4260);
FORCEPROP 0 LASTPIN (-5300 4150) $PN DD11
J 2
(-5310 4160);
DISPLAY 0.489362 (-5310 4160);
PAINT MONO (-5310 4160);
FORCEPROP 0 LASTPIN (-5300 4050) $PN BV9
J 2
(-5310 4060);
DISPLAY 0.489362 (-5310 4060);
PAINT MONO (-5310 4060);
FORCEPROP 0 LASTPIN (-5300 4900) $PN CE9
J 2
(-5310 4910);
DISPLAY 0.489362 (-5310 4910);
PAINT MONO (-5310 4910);
FORCEPROP 0 LASTPIN (-5300 4800) $PN CL9
J 2
(-5310 4810);
DISPLAY 0.489362 (-5310 4810);
PAINT MONO (-5310 4810);
FORCEPROP 0 LASTPIN (-5300 4700) $PN CU9
J 2
(-5310 4710);
DISPLAY 0.489362 (-5310 4710);
PAINT MONO (-5310 4710);
FORCEPROP 0 LASTPIN (-5300 4600) $PN DC9
J 2
(-5310 4610);
DISPLAY 0.489362 (-5310 4610);
PAINT MONO (-5310 4610);
FORCEPROP 0 LASTPIN (-5300 4500) $PN BW10
J 2
(-5310 4510);
DISPLAY 0.489362 (-5310 4510);
PAINT MONO (-5310 4510);
FORCEPROP 0 LASTPIN (-5300 4400) $PN CE10
J 2
(-5310 4410);
DISPLAY 0.489362 (-5310 4410);
PAINT MONO (-5310 4410);
FORCEPROP 0 LASTPIN (-5300 4300) $PN CL10
J 2
(-5310 4310);
DISPLAY 0.489362 (-5310 4310);
PAINT MONO (-5310 4310);
FORCEPROP 0 LASTPIN (-5300 4200) $PN CU10
J 2
(-5310 4210);
DISPLAY 0.489362 (-5310 4210);
PAINT MONO (-5310 4210);
FORCEPROP 0 LASTPIN (-5300 4100) $PN DC10
J 2
(-5310 4110);
DISPLAY 0.489362 (-5310 4110);
PAINT MONO (-5310 4110);
FORCEPROP 0 LASTPIN (-5300 4000) $PN BW9
J 2
(-5310 4010);
DISPLAY 0.489362 (-5310 4010);
PAINT MONO (-5310 4010);
FORCEPROP 0 LASTPIN (-5300 2250) $PN BL10
J 2
(-5310 2260);
DISPLAY 0.489362 (-5310 2260);
PAINT MONO (-5310 2260);
FORCEPROP 0 LASTPIN (-5300 1200) $PN BF11
J 2
(-5310 1210);
DISPLAY 0.489362 (-5310 1210);
PAINT MONO (-5310 1210);
FORCEPROP 2 LAST PART_TYPE SMLF
J 0
(-5150 6400);
DISPLAY 1.021277 (-5150 6400);
FORCEPROP 1 LAST MATERIAL IO
J 0
(-5145 6182);
DISPLAY 0.489362 (-5145 6182);
PAINT SKYBLUE (-5145 6182);
FORCEPROP 2 LAST VALUE SOCKET6096_13568-001
J 0
(-5150 6300);
DISPLAY 0.489362 (-5150 6300);
PAINT SKYBLUE (-5150 6300);
FORCEPROP 1 LAST PART_NUMBER DGA^6000030
J 0
(-5145 6309);
DISPLAY 0.489362 (-5145 6309);
PAINT SKYBLUE (-5145 6309);
FORCEPROP 2 LAST CDS_LIB pure_quanta
J 0
(-4500 3625);
DISPLAY INVISIBLE (-4500 3625);
FORCEPROP 1 LAST CDS_LMAN_SYM_OUTLINE -650,2525,650,-2525
J 0
(-4500 3625);
DISPLAY 0.468085 (-4500 3625);
PAINT GREEN (-4500 3625);
DISPLAY INVISIBLE (-4500 3625);
FORCEPROP 1 LAST NEEDS_NO_SIZE TRUE
J 0
(-4500 3625);
DISPLAY 0.723404 (-4500 3625);
PAINT GREEN (-4500 3625);
DISPLAY INVISIBLE (-4500 3625);
FORCEPROP 1 LAST PATH I159
J 0
(-4500 3625);
DISPLAY 0.723404 (-4500 3625);
PAINT GREEN (-4500 3625);
DISPLAY INVISIBLE (-4500 3625);
FORCEADD OFFPAGE..3
(-2500 6025);
FORCEPROP 2 LAST $XR0 96 
J 0
(-2286 6025);
DISPLAY 0.638298 (-2286 6025);
PAINT MONO (-2286 6025);
FORCEPROP 2 LAST PATH I160
J 0
(-2275 6075);
DISPLAY 1.021277 (-2275 6075);
DISPLAY INVISIBLE (-2275 6075);
FORCEPROP 1 LAST COMMENT_BODY TRUE
J 0
(-2550 5925);
DISPLAY 0.872340 (-2550 5925);
PAINT GREEN (-2550 5925);
DISPLAY INVISIBLE (-2550 5925);
FORCEPROP 1 LAST OFFPAGE TRUE
J 0
(-2175 5900);
DISPLAY 0.872340 (-2175 5900);
PAINT GREEN (-2175 5900);
DISPLAY INVISIBLE (-2175 5900);
FORCEPROP 2 LAST CDS_LIB mstr_standard
J 0
(-2500 6025);
DISPLAY 0.723404 (-2500 6025);
PAINT MONO (-2500 6025);
DISPLAY INVISIBLE (-2500 6025);
FORCEADD OFFPAGE..3
(-2500 4225);
FORCEPROP 2 LAST $XR0 96 
J 0
(-2286 4225);
DISPLAY 0.638298 (-2286 4225);
PAINT MONO (-2286 4225);
FORCEPROP 2 LAST PATH I161
J 0
(-2275 4275);
DISPLAY 1.021277 (-2275 4275);
DISPLAY INVISIBLE (-2275 4275);
FORCEPROP 1 LAST COMMENT_BODY TRUE
J 0
(-2550 4125);
DISPLAY 0.872340 (-2550 4125);
PAINT GREEN (-2550 4125);
DISPLAY INVISIBLE (-2550 4125);
FORCEPROP 1 LAST OFFPAGE TRUE
J 0
(-2175 4100);
DISPLAY 0.872340 (-2175 4100);
PAINT GREEN (-2175 4100);
DISPLAY INVISIBLE (-2175 4100);
FORCEPROP 2 LAST CDS_LIB mstr_standard
J 0
(-2500 4225);
DISPLAY 0.723404 (-2500 4225);
PAINT MONO (-2500 4225);
DISPLAY INVISIBLE (-2500 4225);
FORCEADD TAP..1
(-3225 5950);
FORCEPROP 3 LASTPIN (-3275 5950) SIG_NAME M_L_CPU0_SA_DQ<1>
J 0
(-3265 5960);
DISPLAY 0.659574 (-3265 5960);
PAINT MONO (-3265 5960);
DISPLAY INVISIBLE (-3265 5960);
FORCEPROP 1 LASTPIN (-3275 5950) BN 1
J 0
(-3287 5958);
DISPLAY 0.489362 (-3287 5958);
PAINT GREEN (-3287 5958);
FORCEPROP 2 LAST CDS_LIB mstr_standard
J 0
(-3225 5950);
DISPLAY 0.723404 (-3225 5950);
PAINT MONO (-3225 5950);
DISPLAY INVISIBLE (-3225 5950);
FORCEPROP 1 LAST BODY_TYPE PLUMBING
J 0
(-3225 6000);
DISPLAY 0.872340 (-3225 6000);
PAINT GREEN (-3225 6000);
DISPLAY INVISIBLE (-3225 6000);
FORCEPROP 1 LAST HDL_TAP TRUE
J 0
(-2900 5825);
DISPLAY 0.872340 (-2900 5825);
DISPLAY INVISIBLE (-2900 5825);
FORCEPROP 1 LAST PATH I162
J 0
(-3227 5950);
DISPLAY 0.872340 (-3227 5950);
PAINT GREEN (-3227 5950);
DISPLAY INVISIBLE (-3227 5950);
FORCEADD TAP..1
(-3225 6000);
FORCEPROP 3 LASTPIN (-3275 6000) SIG_NAME M_L_CPU0_SA_DQ<0>
J 0
(-3265 6010);
DISPLAY 0.659574 (-3265 6010);
PAINT MONO (-3265 6010);
DISPLAY INVISIBLE (-3265 6010);
FORCEPROP 1 LASTPIN (-3275 6000) BN 0
J 0
(-3287 6008);
DISPLAY 0.489362 (-3287 6008);
PAINT GREEN (-3287 6008);
FORCEPROP 2 LAST CDS_LIB mstr_standard
J 0
(-3225 6000);
DISPLAY 0.723404 (-3225 6000);
PAINT MONO (-3225 6000);
DISPLAY INVISIBLE (-3225 6000);
FORCEPROP 1 LAST BODY_TYPE PLUMBING
J 0
(-3225 6050);
DISPLAY 0.872340 (-3225 6050);
PAINT GREEN (-3225 6050);
DISPLAY INVISIBLE (-3225 6050);
FORCEPROP 1 LAST HDL_TAP TRUE
J 0
(-2900 5875);
DISPLAY 0.872340 (-2900 5875);
DISPLAY INVISIBLE (-2900 5875);
FORCEPROP 1 LAST PATH I163
J 0
(-3227 6000);
DISPLAY 0.872340 (-3227 6000);
PAINT GREEN (-3227 6000);
DISPLAY INVISIBLE (-3227 6000);
FORCEADD TAP..1
(-3225 5900);
FORCEPROP 3 LASTPIN (-3275 5900) SIG_NAME M_L_CPU0_SA_DQ<2>
J 0
(-3265 5910);
DISPLAY 0.659574 (-3265 5910);
PAINT MONO (-3265 5910);
DISPLAY INVISIBLE (-3265 5910);
FORCEPROP 1 LASTPIN (-3275 5900) BN 2
J 0
(-3287 5908);
DISPLAY 0.489362 (-3287 5908);
PAINT GREEN (-3287 5908);
FORCEPROP 2 LAST CDS_LIB mstr_standard
J 0
(-3225 5900);
DISPLAY 0.723404 (-3225 5900);
PAINT MONO (-3225 5900);
DISPLAY INVISIBLE (-3225 5900);
FORCEPROP 1 LAST BODY_TYPE PLUMBING
J 0
(-3225 5950);
DISPLAY 0.872340 (-3225 5950);
PAINT GREEN (-3225 5950);
DISPLAY INVISIBLE (-3225 5950);
FORCEPROP 1 LAST HDL_TAP TRUE
J 0
(-2900 5775);
DISPLAY 0.872340 (-2900 5775);
DISPLAY INVISIBLE (-2900 5775);
FORCEPROP 1 LAST PATH I164
J 0
(-3227 5900);
DISPLAY 0.872340 (-3227 5900);
PAINT GREEN (-3227 5900);
DISPLAY INVISIBLE (-3227 5900);
FORCEADD TAP..1
(-3225 5850);
FORCEPROP 3 LASTPIN (-3275 5850) SIG_NAME M_L_CPU0_SA_DQ<3>
J 0
(-3265 5860);
DISPLAY 0.659574 (-3265 5860);
PAINT MONO (-3265 5860);
DISPLAY INVISIBLE (-3265 5860);
FORCEPROP 1 LASTPIN (-3275 5850) BN 3
J 0
(-3287 5858);
DISPLAY 0.489362 (-3287 5858);
PAINT GREEN (-3287 5858);
FORCEPROP 2 LAST CDS_LIB mstr_standard
J 0
(-3225 5850);
DISPLAY 0.723404 (-3225 5850);
PAINT MONO (-3225 5850);
DISPLAY INVISIBLE (-3225 5850);
FORCEPROP 1 LAST BODY_TYPE PLUMBING
J 0
(-3225 5900);
DISPLAY 0.872340 (-3225 5900);
PAINT GREEN (-3225 5900);
DISPLAY INVISIBLE (-3225 5900);
FORCEPROP 1 LAST HDL_TAP TRUE
J 0
(-2900 5725);
DISPLAY 0.872340 (-2900 5725);
DISPLAY INVISIBLE (-2900 5725);
FORCEPROP 1 LAST PATH I165
J 0
(-3227 5850);
DISPLAY 0.872340 (-3227 5850);
PAINT GREEN (-3227 5850);
DISPLAY INVISIBLE (-3227 5850);
FORCEADD TAP..1
(-3225 5800);
FORCEPROP 3 LASTPIN (-3275 5800) SIG_NAME M_L_CPU0_SA_DQ<4>
J 0
(-3265 5810);
DISPLAY 0.659574 (-3265 5810);
PAINT MONO (-3265 5810);
DISPLAY INVISIBLE (-3265 5810);
FORCEPROP 1 LASTPIN (-3275 5800) BN 4
J 0
(-3287 5808);
DISPLAY 0.489362 (-3287 5808);
PAINT GREEN (-3287 5808);
FORCEPROP 2 LAST CDS_LIB mstr_standard
J 0
(-3225 5800);
DISPLAY 0.723404 (-3225 5800);
PAINT MONO (-3225 5800);
DISPLAY INVISIBLE (-3225 5800);
FORCEPROP 1 LAST BODY_TYPE PLUMBING
J 0
(-3225 5850);
DISPLAY 0.872340 (-3225 5850);
PAINT GREEN (-3225 5850);
DISPLAY INVISIBLE (-3225 5850);
FORCEPROP 1 LAST HDL_TAP TRUE
J 0
(-2900 5675);
DISPLAY 0.872340 (-2900 5675);
DISPLAY INVISIBLE (-2900 5675);
FORCEPROP 1 LAST PATH I166
J 0
(-3227 5800);
DISPLAY 0.872340 (-3227 5800);
PAINT GREEN (-3227 5800);
DISPLAY INVISIBLE (-3227 5800);
FORCEADD TAP..1
(-3225 5750);
FORCEPROP 3 LASTPIN (-3275 5750) SIG_NAME M_L_CPU0_SA_DQ<5>
J 0
(-3265 5760);
DISPLAY 0.659574 (-3265 5760);
PAINT MONO (-3265 5760);
DISPLAY INVISIBLE (-3265 5760);
FORCEPROP 1 LASTPIN (-3275 5750) BN 5
J 0
(-3287 5758);
DISPLAY 0.489362 (-3287 5758);
PAINT GREEN (-3287 5758);
FORCEPROP 2 LAST CDS_LIB mstr_standard
J 0
(-3225 5750);
DISPLAY 0.723404 (-3225 5750);
PAINT MONO (-3225 5750);
DISPLAY INVISIBLE (-3225 5750);
FORCEPROP 1 LAST BODY_TYPE PLUMBING
J 0
(-3225 5800);
DISPLAY 0.872340 (-3225 5800);
PAINT GREEN (-3225 5800);
DISPLAY INVISIBLE (-3225 5800);
FORCEPROP 1 LAST HDL_TAP TRUE
J 0
(-2900 5625);
DISPLAY 0.872340 (-2900 5625);
DISPLAY INVISIBLE (-2900 5625);
FORCEPROP 1 LAST PATH I167
J 0
(-3227 5750);
DISPLAY 0.872340 (-3227 5750);
PAINT GREEN (-3227 5750);
DISPLAY INVISIBLE (-3227 5750);
FORCEADD TAP..1
(-3225 5700);
FORCEPROP 3 LASTPIN (-3275 5700) SIG_NAME M_L_CPU0_SA_DQ<6>
J 0
(-3265 5710);
DISPLAY 0.659574 (-3265 5710);
PAINT MONO (-3265 5710);
DISPLAY INVISIBLE (-3265 5710);
FORCEPROP 1 LASTPIN (-3275 5700) BN 6
J 0
(-3287 5708);
DISPLAY 0.489362 (-3287 5708);
PAINT GREEN (-3287 5708);
FORCEPROP 2 LAST CDS_LIB mstr_standard
J 0
(-3225 5700);
DISPLAY 0.723404 (-3225 5700);
PAINT MONO (-3225 5700);
DISPLAY INVISIBLE (-3225 5700);
FORCEPROP 1 LAST BODY_TYPE PLUMBING
J 0
(-3225 5750);
DISPLAY 0.872340 (-3225 5750);
PAINT GREEN (-3225 5750);
DISPLAY INVISIBLE (-3225 5750);
FORCEPROP 1 LAST HDL_TAP TRUE
J 0
(-2900 5575);
DISPLAY 0.872340 (-2900 5575);
DISPLAY INVISIBLE (-2900 5575);
FORCEPROP 1 LAST PATH I168
J 0
(-3227 5700);
DISPLAY 0.872340 (-3227 5700);
PAINT GREEN (-3227 5700);
DISPLAY INVISIBLE (-3227 5700);
FORCEADD TAP..1
(-3225 5650);
FORCEPROP 3 LASTPIN (-3275 5650) SIG_NAME M_L_CPU0_SA_DQ<7>
J 0
(-3265 5660);
DISPLAY 0.659574 (-3265 5660);
PAINT MONO (-3265 5660);
DISPLAY INVISIBLE (-3265 5660);
FORCEPROP 1 LASTPIN (-3275 5650) BN 7
J 0
(-3287 5658);
DISPLAY 0.489362 (-3287 5658);
PAINT GREEN (-3287 5658);
FORCEPROP 2 LAST CDS_LIB mstr_standard
J 0
(-3225 5650);
DISPLAY 0.723404 (-3225 5650);
PAINT MONO (-3225 5650);
DISPLAY INVISIBLE (-3225 5650);
FORCEPROP 1 LAST BODY_TYPE PLUMBING
J 0
(-3225 5700);
DISPLAY 0.872340 (-3225 5700);
PAINT GREEN (-3225 5700);
DISPLAY INVISIBLE (-3225 5700);
FORCEPROP 1 LAST HDL_TAP TRUE
J 0
(-2900 5525);
DISPLAY 0.872340 (-2900 5525);
DISPLAY INVISIBLE (-2900 5525);
FORCEPROP 1 LAST PATH I169
J 0
(-3227 5650);
DISPLAY 0.872340 (-3227 5650);
PAINT GREEN (-3227 5650);
DISPLAY INVISIBLE (-3227 5650);
FORCEADD TAP..1
(-3225 5450);
FORCEPROP 3 LASTPIN (-3275 5450) SIG_NAME M_L_CPU0_SA_DQ<10>
J 0
(-3265 5460);
DISPLAY 0.659574 (-3265 5460);
PAINT MONO (-3265 5460);
DISPLAY INVISIBLE (-3265 5460);
FORCEPROP 1 LASTPIN (-3275 5450) BN 10
J 0
(-3287 5458);
DISPLAY 0.489362 (-3287 5458);
PAINT GREEN (-3287 5458);
FORCEPROP 2 LAST CDS_LIB mstr_standard
J 0
(-3225 5450);
DISPLAY 0.723404 (-3225 5450);
PAINT MONO (-3225 5450);
DISPLAY INVISIBLE (-3225 5450);
FORCEPROP 1 LAST BODY_TYPE PLUMBING
J 0
(-3225 5500);
DISPLAY 0.872340 (-3225 5500);
PAINT GREEN (-3225 5500);
DISPLAY INVISIBLE (-3225 5500);
FORCEPROP 1 LAST HDL_TAP TRUE
J 0
(-2900 5325);
DISPLAY 0.872340 (-2900 5325);
DISPLAY INVISIBLE (-2900 5325);
FORCEPROP 1 LAST PATH I170
J 0
(-3227 5450);
DISPLAY 0.872340 (-3227 5450);
PAINT GREEN (-3227 5450);
DISPLAY INVISIBLE (-3227 5450);
FORCEADD TAP..1
(-3225 5500);
FORCEPROP 3 LASTPIN (-3275 5500) SIG_NAME M_L_CPU0_SA_DQ<9>
J 0
(-3265 5510);
DISPLAY 0.659574 (-3265 5510);
PAINT MONO (-3265 5510);
DISPLAY INVISIBLE (-3265 5510);
FORCEPROP 1 LASTPIN (-3275 5500) BN 9
J 0
(-3287 5508);
DISPLAY 0.489362 (-3287 5508);
PAINT GREEN (-3287 5508);
FORCEPROP 2 LAST CDS_LIB mstr_standard
J 0
(-3225 5500);
DISPLAY 0.723404 (-3225 5500);
PAINT MONO (-3225 5500);
DISPLAY INVISIBLE (-3225 5500);
FORCEPROP 1 LAST BODY_TYPE PLUMBING
J 0
(-3225 5550);
DISPLAY 0.872340 (-3225 5550);
PAINT GREEN (-3225 5550);
DISPLAY INVISIBLE (-3225 5550);
FORCEPROP 1 LAST HDL_TAP TRUE
J 0
(-2900 5375);
DISPLAY 0.872340 (-2900 5375);
DISPLAY INVISIBLE (-2900 5375);
FORCEPROP 1 LAST PATH I171
J 0
(-3227 5500);
DISPLAY 0.872340 (-3227 5500);
PAINT GREEN (-3227 5500);
DISPLAY INVISIBLE (-3227 5500);
FORCEADD TAP..1
(-3225 5550);
FORCEPROP 3 LASTPIN (-3275 5550) SIG_NAME M_L_CPU0_SA_DQ<8>
J 0
(-3265 5560);
DISPLAY 0.659574 (-3265 5560);
PAINT MONO (-3265 5560);
DISPLAY INVISIBLE (-3265 5560);
FORCEPROP 1 LASTPIN (-3275 5550) BN 8
J 0
(-3287 5558);
DISPLAY 0.489362 (-3287 5558);
PAINT GREEN (-3287 5558);
FORCEPROP 2 LAST CDS_LIB mstr_standard
J 0
(-3225 5550);
DISPLAY 0.723404 (-3225 5550);
PAINT MONO (-3225 5550);
DISPLAY INVISIBLE (-3225 5550);
FORCEPROP 1 LAST BODY_TYPE PLUMBING
J 0
(-3225 5600);
DISPLAY 0.872340 (-3225 5600);
PAINT GREEN (-3225 5600);
DISPLAY INVISIBLE (-3225 5600);
FORCEPROP 1 LAST HDL_TAP TRUE
J 0
(-2900 5425);
DISPLAY 0.872340 (-2900 5425);
DISPLAY INVISIBLE (-2900 5425);
FORCEPROP 1 LAST PATH I172
J 0
(-3227 5550);
DISPLAY 0.872340 (-3227 5550);
PAINT GREEN (-3227 5550);
DISPLAY INVISIBLE (-3227 5550);
FORCEADD TAP..1
(-3225 5400);
FORCEPROP 3 LASTPIN (-3275 5400) SIG_NAME M_L_CPU0_SA_DQ<11>
J 0
(-3265 5410);
DISPLAY 0.659574 (-3265 5410);
PAINT MONO (-3265 5410);
DISPLAY INVISIBLE (-3265 5410);
FORCEPROP 1 LASTPIN (-3275 5400) BN 11
J 0
(-3287 5408);
DISPLAY 0.489362 (-3287 5408);
PAINT GREEN (-3287 5408);
FORCEPROP 2 LAST CDS_LIB mstr_standard
J 0
(-3225 5400);
DISPLAY 0.723404 (-3225 5400);
PAINT MONO (-3225 5400);
DISPLAY INVISIBLE (-3225 5400);
FORCEPROP 1 LAST BODY_TYPE PLUMBING
J 0
(-3225 5450);
DISPLAY 0.872340 (-3225 5450);
PAINT GREEN (-3225 5450);
DISPLAY INVISIBLE (-3225 5450);
FORCEPROP 1 LAST HDL_TAP TRUE
J 0
(-2900 5275);
DISPLAY 0.872340 (-2900 5275);
DISPLAY INVISIBLE (-2900 5275);
FORCEPROP 1 LAST PATH I173
J 0
(-3227 5400);
DISPLAY 0.872340 (-3227 5400);
PAINT GREEN (-3227 5400);
DISPLAY INVISIBLE (-3227 5400);
FORCEADD TAP..1
(-3225 5300);
FORCEPROP 3 LASTPIN (-3275 5300) SIG_NAME M_L_CPU0_SA_DQ<13>
J 0
(-3265 5310);
DISPLAY 0.659574 (-3265 5310);
PAINT MONO (-3265 5310);
DISPLAY INVISIBLE (-3265 5310);
FORCEPROP 1 LASTPIN (-3275 5300) BN 13
J 0
(-3287 5308);
DISPLAY 0.489362 (-3287 5308);
PAINT GREEN (-3287 5308);
FORCEPROP 2 LAST CDS_LIB mstr_standard
J 0
(-3225 5300);
DISPLAY 0.723404 (-3225 5300);
PAINT MONO (-3225 5300);
DISPLAY INVISIBLE (-3225 5300);
FORCEPROP 1 LAST BODY_TYPE PLUMBING
J 0
(-3225 5350);
DISPLAY 0.872340 (-3225 5350);
PAINT GREEN (-3225 5350);
DISPLAY INVISIBLE (-3225 5350);
FORCEPROP 1 LAST HDL_TAP TRUE
J 0
(-2900 5175);
DISPLAY 0.872340 (-2900 5175);
DISPLAY INVISIBLE (-2900 5175);
FORCEPROP 1 LAST PATH I174
J 0
(-3227 5300);
DISPLAY 0.872340 (-3227 5300);
PAINT GREEN (-3227 5300);
DISPLAY INVISIBLE (-3227 5300);
FORCEADD TAP..1
(-3225 5350);
FORCEPROP 3 LASTPIN (-3275 5350) SIG_NAME M_L_CPU0_SA_DQ<12>
J 0
(-3265 5360);
DISPLAY 0.659574 (-3265 5360);
PAINT MONO (-3265 5360);
DISPLAY INVISIBLE (-3265 5360);
FORCEPROP 1 LASTPIN (-3275 5350) BN 12
J 0
(-3287 5358);
DISPLAY 0.489362 (-3287 5358);
PAINT GREEN (-3287 5358);
FORCEPROP 2 LAST CDS_LIB mstr_standard
J 0
(-3225 5350);
DISPLAY 0.723404 (-3225 5350);
PAINT MONO (-3225 5350);
DISPLAY INVISIBLE (-3225 5350);
FORCEPROP 1 LAST BODY_TYPE PLUMBING
J 0
(-3225 5400);
DISPLAY 0.872340 (-3225 5400);
PAINT GREEN (-3225 5400);
DISPLAY INVISIBLE (-3225 5400);
FORCEPROP 1 LAST HDL_TAP TRUE
J 0
(-2900 5225);
DISPLAY 0.872340 (-2900 5225);
DISPLAY INVISIBLE (-2900 5225);
FORCEPROP 1 LAST PATH I175
J 0
(-3227 5350);
DISPLAY 0.872340 (-3227 5350);
PAINT GREEN (-3227 5350);
DISPLAY INVISIBLE (-3227 5350);
FORCEADD TAP..1
(-3225 5200);
FORCEPROP 3 LASTPIN (-3275 5200) SIG_NAME M_L_CPU0_SA_DQ<15>
J 0
(-3265 5210);
DISPLAY 0.659574 (-3265 5210);
PAINT MONO (-3265 5210);
DISPLAY INVISIBLE (-3265 5210);
FORCEPROP 1 LASTPIN (-3275 5200) BN 15
J 0
(-3287 5208);
DISPLAY 0.489362 (-3287 5208);
PAINT GREEN (-3287 5208);
FORCEPROP 2 LAST CDS_LIB mstr_standard
J 0
(-3225 5200);
DISPLAY 0.723404 (-3225 5200);
PAINT MONO (-3225 5200);
DISPLAY INVISIBLE (-3225 5200);
FORCEPROP 1 LAST BODY_TYPE PLUMBING
J 0
(-3225 5250);
DISPLAY 0.872340 (-3225 5250);
PAINT GREEN (-3225 5250);
DISPLAY INVISIBLE (-3225 5250);
FORCEPROP 1 LAST HDL_TAP TRUE
J 0
(-2900 5075);
DISPLAY 0.872340 (-2900 5075);
DISPLAY INVISIBLE (-2900 5075);
FORCEPROP 1 LAST PATH I176
J 0
(-3227 5200);
DISPLAY 0.872340 (-3227 5200);
PAINT GREEN (-3227 5200);
DISPLAY INVISIBLE (-3227 5200);
FORCEADD TAP..1
(-3225 5250);
FORCEPROP 3 LASTPIN (-3275 5250) SIG_NAME M_L_CPU0_SA_DQ<14>
J 0
(-3265 5260);
DISPLAY 0.659574 (-3265 5260);
PAINT MONO (-3265 5260);
DISPLAY INVISIBLE (-3265 5260);
FORCEPROP 1 LASTPIN (-3275 5250) BN 14
J 0
(-3287 5258);
DISPLAY 0.489362 (-3287 5258);
PAINT GREEN (-3287 5258);
FORCEPROP 2 LAST CDS_LIB mstr_standard
J 0
(-3225 5250);
DISPLAY 0.723404 (-3225 5250);
PAINT MONO (-3225 5250);
DISPLAY INVISIBLE (-3225 5250);
FORCEPROP 1 LAST BODY_TYPE PLUMBING
J 0
(-3225 5300);
DISPLAY 0.872340 (-3225 5300);
PAINT GREEN (-3225 5300);
DISPLAY INVISIBLE (-3225 5300);
FORCEPROP 1 LAST HDL_TAP TRUE
J 0
(-2900 5125);
DISPLAY 0.872340 (-2900 5125);
DISPLAY INVISIBLE (-2900 5125);
FORCEPROP 1 LAST PATH I177
J 0
(-3227 5250);
DISPLAY 0.872340 (-3227 5250);
PAINT GREEN (-3227 5250);
DISPLAY INVISIBLE (-3227 5250);
FORCEADD TAP..1
(-3225 5100);
FORCEPROP 3 LASTPIN (-3275 5100) SIG_NAME M_L_CPU0_SA_DQ<16>
J 0
(-3265 5110);
DISPLAY 0.659574 (-3265 5110);
PAINT MONO (-3265 5110);
DISPLAY INVISIBLE (-3265 5110);
FORCEPROP 1 LASTPIN (-3275 5100) BN 16
J 0
(-3287 5108);
DISPLAY 0.489362 (-3287 5108);
PAINT GREEN (-3287 5108);
FORCEPROP 2 LAST CDS_LIB mstr_standard
J 0
(-3225 5100);
DISPLAY 0.723404 (-3225 5100);
PAINT MONO (-3225 5100);
DISPLAY INVISIBLE (-3225 5100);
FORCEPROP 1 LAST BODY_TYPE PLUMBING
J 0
(-3225 5150);
DISPLAY 0.872340 (-3225 5150);
PAINT GREEN (-3225 5150);
DISPLAY INVISIBLE (-3225 5150);
FORCEPROP 1 LAST HDL_TAP TRUE
J 0
(-2900 4975);
DISPLAY 0.872340 (-2900 4975);
DISPLAY INVISIBLE (-2900 4975);
FORCEPROP 1 LAST PATH I178
J 0
(-3227 5100);
DISPLAY 0.872340 (-3227 5100);
PAINT GREEN (-3227 5100);
DISPLAY INVISIBLE (-3227 5100);
FORCEADD TAP..1
(-3225 5050);
FORCEPROP 3 LASTPIN (-3275 5050) SIG_NAME M_L_CPU0_SA_DQ<17>
J 0
(-3265 5060);
DISPLAY 0.659574 (-3265 5060);
PAINT MONO (-3265 5060);
DISPLAY INVISIBLE (-3265 5060);
FORCEPROP 1 LASTPIN (-3275 5050) BN 17
J 0
(-3287 5058);
DISPLAY 0.489362 (-3287 5058);
PAINT GREEN (-3287 5058);
FORCEPROP 2 LAST CDS_LIB mstr_standard
J 0
(-3225 5050);
DISPLAY 0.723404 (-3225 5050);
PAINT MONO (-3225 5050);
DISPLAY INVISIBLE (-3225 5050);
FORCEPROP 1 LAST BODY_TYPE PLUMBING
J 0
(-3225 5100);
DISPLAY 0.872340 (-3225 5100);
PAINT GREEN (-3225 5100);
DISPLAY INVISIBLE (-3225 5100);
FORCEPROP 1 LAST HDL_TAP TRUE
J 0
(-2900 4925);
DISPLAY 0.872340 (-2900 4925);
DISPLAY INVISIBLE (-2900 4925);
FORCEPROP 1 LAST PATH I179
J 0
(-3227 5050);
DISPLAY 0.872340 (-3227 5050);
PAINT GREEN (-3227 5050);
DISPLAY INVISIBLE (-3227 5050);
FORCEADD TAP..1
(-3225 5000);
FORCEPROP 3 LASTPIN (-3275 5000) SIG_NAME M_L_CPU0_SA_DQ<18>
J 0
(-3265 5010);
DISPLAY 0.659574 (-3265 5010);
PAINT MONO (-3265 5010);
DISPLAY INVISIBLE (-3265 5010);
FORCEPROP 1 LASTPIN (-3275 5000) BN 18
J 0
(-3287 5008);
DISPLAY 0.489362 (-3287 5008);
PAINT GREEN (-3287 5008);
FORCEPROP 2 LAST CDS_LIB mstr_standard
J 0
(-3225 5000);
DISPLAY 0.723404 (-3225 5000);
PAINT MONO (-3225 5000);
DISPLAY INVISIBLE (-3225 5000);
FORCEPROP 1 LAST BODY_TYPE PLUMBING
J 0
(-3225 5050);
DISPLAY 0.872340 (-3225 5050);
PAINT GREEN (-3225 5050);
DISPLAY INVISIBLE (-3225 5050);
FORCEPROP 1 LAST HDL_TAP TRUE
J 0
(-2900 4875);
DISPLAY 0.872340 (-2900 4875);
DISPLAY INVISIBLE (-2900 4875);
FORCEPROP 1 LAST PATH I180
J 0
(-3227 5000);
DISPLAY 0.872340 (-3227 5000);
PAINT GREEN (-3227 5000);
DISPLAY INVISIBLE (-3227 5000);
FORCEADD TAP..1
(-3225 4950);
FORCEPROP 3 LASTPIN (-3275 4950) SIG_NAME M_L_CPU0_SA_DQ<19>
J 0
(-3265 4960);
DISPLAY 0.659574 (-3265 4960);
PAINT MONO (-3265 4960);
DISPLAY INVISIBLE (-3265 4960);
FORCEPROP 1 LASTPIN (-3275 4950) BN 19
J 0
(-3287 4958);
DISPLAY 0.489362 (-3287 4958);
PAINT GREEN (-3287 4958);
FORCEPROP 2 LAST CDS_LIB mstr_standard
J 0
(-3225 4950);
DISPLAY 0.723404 (-3225 4950);
PAINT MONO (-3225 4950);
DISPLAY INVISIBLE (-3225 4950);
FORCEPROP 1 LAST BODY_TYPE PLUMBING
J 0
(-3225 5000);
DISPLAY 0.872340 (-3225 5000);
PAINT GREEN (-3225 5000);
DISPLAY INVISIBLE (-3225 5000);
FORCEPROP 1 LAST HDL_TAP TRUE
J 0
(-2900 4825);
DISPLAY 0.872340 (-2900 4825);
DISPLAY INVISIBLE (-2900 4825);
FORCEPROP 1 LAST PATH I181
J 0
(-3227 4950);
DISPLAY 0.872340 (-3227 4950);
PAINT GREEN (-3227 4950);
DISPLAY INVISIBLE (-3227 4950);
FORCEADD TAP..1
(-3225 4900);
FORCEPROP 3 LASTPIN (-3275 4900) SIG_NAME M_L_CPU0_SA_DQ<20>
J 0
(-3265 4910);
DISPLAY 0.659574 (-3265 4910);
PAINT MONO (-3265 4910);
DISPLAY INVISIBLE (-3265 4910);
FORCEPROP 1 LASTPIN (-3275 4900) BN 20
J 0
(-3287 4908);
DISPLAY 0.489362 (-3287 4908);
PAINT GREEN (-3287 4908);
FORCEPROP 2 LAST CDS_LIB mstr_standard
J 0
(-3225 4900);
DISPLAY 0.723404 (-3225 4900);
PAINT MONO (-3225 4900);
DISPLAY INVISIBLE (-3225 4900);
FORCEPROP 1 LAST BODY_TYPE PLUMBING
J 0
(-3225 4950);
DISPLAY 0.872340 (-3225 4950);
PAINT GREEN (-3225 4950);
DISPLAY INVISIBLE (-3225 4950);
FORCEPROP 1 LAST HDL_TAP TRUE
J 0
(-2900 4775);
DISPLAY 0.872340 (-2900 4775);
DISPLAY INVISIBLE (-2900 4775);
FORCEPROP 1 LAST PATH I182
J 0
(-3227 4900);
DISPLAY 0.872340 (-3227 4900);
PAINT GREEN (-3227 4900);
DISPLAY INVISIBLE (-3227 4900);
FORCEADD TAP..1
(-3225 4800);
FORCEPROP 3 LASTPIN (-3275 4800) SIG_NAME M_L_CPU0_SA_DQ<22>
J 0
(-3265 4810);
DISPLAY 0.659574 (-3265 4810);
PAINT MONO (-3265 4810);
DISPLAY INVISIBLE (-3265 4810);
FORCEPROP 1 LASTPIN (-3275 4800) BN 22
J 0
(-3287 4808);
DISPLAY 0.489362 (-3287 4808);
PAINT GREEN (-3287 4808);
FORCEPROP 2 LAST CDS_LIB mstr_standard
J 0
(-3225 4800);
DISPLAY 0.723404 (-3225 4800);
PAINT MONO (-3225 4800);
DISPLAY INVISIBLE (-3225 4800);
FORCEPROP 1 LAST BODY_TYPE PLUMBING
J 0
(-3225 4850);
DISPLAY 0.872340 (-3225 4850);
PAINT GREEN (-3225 4850);
DISPLAY INVISIBLE (-3225 4850);
FORCEPROP 1 LAST HDL_TAP TRUE
J 0
(-2900 4675);
DISPLAY 0.872340 (-2900 4675);
DISPLAY INVISIBLE (-2900 4675);
FORCEPROP 1 LAST PATH I183
J 0
(-3227 4800);
DISPLAY 0.872340 (-3227 4800);
PAINT GREEN (-3227 4800);
DISPLAY INVISIBLE (-3227 4800);
FORCEADD TAP..1
(-3225 4850);
FORCEPROP 3 LASTPIN (-3275 4850) SIG_NAME M_L_CPU0_SA_DQ<21>
J 0
(-3265 4860);
DISPLAY 0.659574 (-3265 4860);
PAINT MONO (-3265 4860);
DISPLAY INVISIBLE (-3265 4860);
FORCEPROP 1 LASTPIN (-3275 4850) BN 21
J 0
(-3287 4858);
DISPLAY 0.489362 (-3287 4858);
PAINT GREEN (-3287 4858);
FORCEPROP 2 LAST CDS_LIB mstr_standard
J 0
(-3225 4850);
DISPLAY 0.723404 (-3225 4850);
PAINT MONO (-3225 4850);
DISPLAY INVISIBLE (-3225 4850);
FORCEPROP 1 LAST BODY_TYPE PLUMBING
J 0
(-3225 4900);
DISPLAY 0.872340 (-3225 4900);
PAINT GREEN (-3225 4900);
DISPLAY INVISIBLE (-3225 4900);
FORCEPROP 1 LAST HDL_TAP TRUE
J 0
(-2900 4725);
DISPLAY 0.872340 (-2900 4725);
DISPLAY INVISIBLE (-2900 4725);
FORCEPROP 1 LAST PATH I184
J 0
(-3227 4850);
DISPLAY 0.872340 (-3227 4850);
PAINT GREEN (-3227 4850);
DISPLAY INVISIBLE (-3227 4850);
FORCEADD TAP..1
(-3225 4750);
FORCEPROP 3 LASTPIN (-3275 4750) SIG_NAME M_L_CPU0_SA_DQ<23>
J 0
(-3265 4760);
DISPLAY 0.659574 (-3265 4760);
PAINT MONO (-3265 4760);
DISPLAY INVISIBLE (-3265 4760);
FORCEPROP 1 LASTPIN (-3275 4750) BN 23
J 0
(-3287 4758);
DISPLAY 0.489362 (-3287 4758);
PAINT GREEN (-3287 4758);
FORCEPROP 2 LAST CDS_LIB mstr_standard
J 0
(-3225 4750);
DISPLAY 0.723404 (-3225 4750);
PAINT MONO (-3225 4750);
DISPLAY INVISIBLE (-3225 4750);
FORCEPROP 1 LAST BODY_TYPE PLUMBING
J 0
(-3225 4800);
DISPLAY 0.872340 (-3225 4800);
PAINT GREEN (-3225 4800);
DISPLAY INVISIBLE (-3225 4800);
FORCEPROP 1 LAST HDL_TAP TRUE
J 0
(-2900 4625);
DISPLAY 0.872340 (-2900 4625);
DISPLAY INVISIBLE (-2900 4625);
FORCEPROP 1 LAST PATH I185
J 0
(-3227 4750);
DISPLAY 0.872340 (-3227 4750);
PAINT GREEN (-3227 4750);
DISPLAY INVISIBLE (-3227 4750);
FORCEADD TAP..1
(-3225 4650);
FORCEPROP 3 LASTPIN (-3275 4650) SIG_NAME M_L_CPU0_SA_DQ<24>
J 0
(-3265 4660);
DISPLAY 0.659574 (-3265 4660);
PAINT MONO (-3265 4660);
DISPLAY INVISIBLE (-3265 4660);
FORCEPROP 1 LASTPIN (-3275 4650) BN 24
J 0
(-3287 4658);
DISPLAY 0.489362 (-3287 4658);
PAINT GREEN (-3287 4658);
FORCEPROP 2 LAST CDS_LIB mstr_standard
J 0
(-3225 4650);
DISPLAY 0.723404 (-3225 4650);
PAINT MONO (-3225 4650);
DISPLAY INVISIBLE (-3225 4650);
FORCEPROP 1 LAST BODY_TYPE PLUMBING
J 0
(-3225 4700);
DISPLAY 0.872340 (-3225 4700);
PAINT GREEN (-3225 4700);
DISPLAY INVISIBLE (-3225 4700);
FORCEPROP 1 LAST HDL_TAP TRUE
J 0
(-2900 4525);
DISPLAY 0.872340 (-2900 4525);
DISPLAY INVISIBLE (-2900 4525);
FORCEPROP 1 LAST PATH I186
J 0
(-3227 4650);
DISPLAY 0.872340 (-3227 4650);
PAINT GREEN (-3227 4650);
DISPLAY INVISIBLE (-3227 4650);
FORCEADD TAP..1
(-3225 4550);
FORCEPROP 3 LASTPIN (-3275 4550) SIG_NAME M_L_CPU0_SA_DQ<26>
J 0
(-3265 4560);
DISPLAY 0.659574 (-3265 4560);
PAINT MONO (-3265 4560);
DISPLAY INVISIBLE (-3265 4560);
FORCEPROP 1 LASTPIN (-3275 4550) BN 26
J 0
(-3287 4558);
DISPLAY 0.489362 (-3287 4558);
PAINT GREEN (-3287 4558);
FORCEPROP 2 LAST CDS_LIB mstr_standard
J 0
(-3225 4550);
DISPLAY 0.723404 (-3225 4550);
PAINT MONO (-3225 4550);
DISPLAY INVISIBLE (-3225 4550);
FORCEPROP 1 LAST BODY_TYPE PLUMBING
J 0
(-3225 4600);
DISPLAY 0.872340 (-3225 4600);
PAINT GREEN (-3225 4600);
DISPLAY INVISIBLE (-3225 4600);
FORCEPROP 1 LAST HDL_TAP TRUE
J 0
(-2900 4425);
DISPLAY 0.872340 (-2900 4425);
DISPLAY INVISIBLE (-2900 4425);
FORCEPROP 1 LAST PATH I187
J 0
(-3227 4550);
DISPLAY 0.872340 (-3227 4550);
PAINT GREEN (-3227 4550);
DISPLAY INVISIBLE (-3227 4550);
FORCEADD TAP..1
(-3225 4600);
FORCEPROP 3 LASTPIN (-3275 4600) SIG_NAME M_L_CPU0_SA_DQ<25>
J 0
(-3265 4610);
DISPLAY 0.659574 (-3265 4610);
PAINT MONO (-3265 4610);
DISPLAY INVISIBLE (-3265 4610);
FORCEPROP 1 LASTPIN (-3275 4600) BN 25
J 0
(-3287 4608);
DISPLAY 0.489362 (-3287 4608);
PAINT GREEN (-3287 4608);
FORCEPROP 2 LAST CDS_LIB mstr_standard
J 0
(-3225 4600);
DISPLAY 0.723404 (-3225 4600);
PAINT MONO (-3225 4600);
DISPLAY INVISIBLE (-3225 4600);
FORCEPROP 1 LAST BODY_TYPE PLUMBING
J 0
(-3225 4650);
DISPLAY 0.872340 (-3225 4650);
PAINT GREEN (-3225 4650);
DISPLAY INVISIBLE (-3225 4650);
FORCEPROP 1 LAST HDL_TAP TRUE
J 0
(-2900 4475);
DISPLAY 0.872340 (-2900 4475);
DISPLAY INVISIBLE (-2900 4475);
FORCEPROP 1 LAST PATH I188
J 0
(-3227 4600);
DISPLAY 0.872340 (-3227 4600);
PAINT GREEN (-3227 4600);
DISPLAY INVISIBLE (-3227 4600);
FORCEADD TAP..1
(-3225 4500);
FORCEPROP 3 LASTPIN (-3275 4500) SIG_NAME M_L_CPU0_SA_DQ<27>
J 0
(-3265 4510);
DISPLAY 0.659574 (-3265 4510);
PAINT MONO (-3265 4510);
DISPLAY INVISIBLE (-3265 4510);
FORCEPROP 1 LASTPIN (-3275 4500) BN 27
J 0
(-3287 4508);
DISPLAY 0.489362 (-3287 4508);
PAINT GREEN (-3287 4508);
FORCEPROP 2 LAST CDS_LIB mstr_standard
J 0
(-3225 4500);
DISPLAY 0.723404 (-3225 4500);
PAINT MONO (-3225 4500);
DISPLAY INVISIBLE (-3225 4500);
FORCEPROP 1 LAST BODY_TYPE PLUMBING
J 0
(-3225 4550);
DISPLAY 0.872340 (-3225 4550);
PAINT GREEN (-3225 4550);
DISPLAY INVISIBLE (-3225 4550);
FORCEPROP 1 LAST HDL_TAP TRUE
J 0
(-2900 4375);
DISPLAY 0.872340 (-2900 4375);
DISPLAY INVISIBLE (-2900 4375);
FORCEPROP 1 LAST PATH I189
J 0
(-3227 4500);
DISPLAY 0.872340 (-3227 4500);
PAINT GREEN (-3227 4500);
DISPLAY INVISIBLE (-3227 4500);
FORCEADD TAP..1
(-3225 4450);
FORCEPROP 3 LASTPIN (-3275 4450) SIG_NAME M_L_CPU0_SA_DQ<28>
J 0
(-3265 4460);
DISPLAY 0.659574 (-3265 4460);
PAINT MONO (-3265 4460);
DISPLAY INVISIBLE (-3265 4460);
FORCEPROP 1 LASTPIN (-3275 4450) BN 28
J 0
(-3287 4458);
DISPLAY 0.489362 (-3287 4458);
PAINT GREEN (-3287 4458);
FORCEPROP 2 LAST CDS_LIB mstr_standard
J 0
(-3225 4450);
DISPLAY 0.723404 (-3225 4450);
PAINT MONO (-3225 4450);
DISPLAY INVISIBLE (-3225 4450);
FORCEPROP 1 LAST BODY_TYPE PLUMBING
J 0
(-3225 4500);
DISPLAY 0.872340 (-3225 4500);
PAINT GREEN (-3225 4500);
DISPLAY INVISIBLE (-3225 4500);
FORCEPROP 1 LAST HDL_TAP TRUE
J 0
(-2900 4325);
DISPLAY 0.872340 (-2900 4325);
DISPLAY INVISIBLE (-2900 4325);
FORCEPROP 1 LAST PATH I190
J 0
(-3227 4450);
DISPLAY 0.872340 (-3227 4450);
PAINT GREEN (-3227 4450);
DISPLAY INVISIBLE (-3227 4450);
FORCEADD TAP..1
(-3225 4400);
FORCEPROP 3 LASTPIN (-3275 4400) SIG_NAME M_L_CPU0_SA_DQ<29>
J 0
(-3265 4410);
DISPLAY 0.659574 (-3265 4410);
PAINT MONO (-3265 4410);
DISPLAY INVISIBLE (-3265 4410);
FORCEPROP 1 LASTPIN (-3275 4400) BN 29
J 0
(-3287 4408);
DISPLAY 0.489362 (-3287 4408);
PAINT GREEN (-3287 4408);
FORCEPROP 2 LAST CDS_LIB mstr_standard
J 0
(-3225 4400);
DISPLAY 0.723404 (-3225 4400);
PAINT MONO (-3225 4400);
DISPLAY INVISIBLE (-3225 4400);
FORCEPROP 1 LAST BODY_TYPE PLUMBING
J 0
(-3225 4450);
DISPLAY 0.872340 (-3225 4450);
PAINT GREEN (-3225 4450);
DISPLAY INVISIBLE (-3225 4450);
FORCEPROP 1 LAST HDL_TAP TRUE
J 0
(-2900 4275);
DISPLAY 0.872340 (-2900 4275);
DISPLAY INVISIBLE (-2900 4275);
FORCEPROP 1 LAST PATH I191
J 0
(-3227 4400);
DISPLAY 0.872340 (-3227 4400);
PAINT GREEN (-3227 4400);
DISPLAY INVISIBLE (-3227 4400);
FORCEADD TAP..1
(-3225 4300);
FORCEPROP 3 LASTPIN (-3275 4300) SIG_NAME M_L_CPU0_SA_DQ<31>
J 0
(-3265 4310);
DISPLAY 0.659574 (-3265 4310);
PAINT MONO (-3265 4310);
DISPLAY INVISIBLE (-3265 4310);
FORCEPROP 1 LASTPIN (-3275 4300) BN 31
J 0
(-3287 4308);
DISPLAY 0.489362 (-3287 4308);
PAINT GREEN (-3287 4308);
FORCEPROP 2 LAST CDS_LIB mstr_standard
J 0
(-3225 4300);
DISPLAY 0.723404 (-3225 4300);
PAINT MONO (-3225 4300);
DISPLAY INVISIBLE (-3225 4300);
FORCEPROP 1 LAST BODY_TYPE PLUMBING
J 0
(-3225 4350);
DISPLAY 0.872340 (-3225 4350);
PAINT GREEN (-3225 4350);
DISPLAY INVISIBLE (-3225 4350);
FORCEPROP 1 LAST HDL_TAP TRUE
J 0
(-2900 4175);
DISPLAY 0.872340 (-2900 4175);
DISPLAY INVISIBLE (-2900 4175);
FORCEPROP 1 LAST PATH I192
J 0
(-3227 4300);
DISPLAY 0.872340 (-3227 4300);
PAINT GREEN (-3227 4300);
DISPLAY INVISIBLE (-3227 4300);
FORCEADD TAP..1
(-3225 4350);
FORCEPROP 3 LASTPIN (-3275 4350) SIG_NAME M_L_CPU0_SA_DQ<30>
J 0
(-3265 4360);
DISPLAY 0.659574 (-3265 4360);
PAINT MONO (-3265 4360);
DISPLAY INVISIBLE (-3265 4360);
FORCEPROP 1 LASTPIN (-3275 4350) BN 30
J 0
(-3287 4358);
DISPLAY 0.489362 (-3287 4358);
PAINT GREEN (-3287 4358);
FORCEPROP 2 LAST CDS_LIB mstr_standard
J 0
(-3225 4350);
DISPLAY 0.723404 (-3225 4350);
PAINT MONO (-3225 4350);
DISPLAY INVISIBLE (-3225 4350);
FORCEPROP 1 LAST BODY_TYPE PLUMBING
J 0
(-3225 4400);
DISPLAY 0.872340 (-3225 4400);
PAINT GREEN (-3225 4400);
DISPLAY INVISIBLE (-3225 4400);
FORCEPROP 1 LAST HDL_TAP TRUE
J 0
(-2900 4225);
DISPLAY 0.872340 (-2900 4225);
DISPLAY INVISIBLE (-2900 4225);
FORCEPROP 1 LAST PATH I193
J 0
(-3227 4350);
DISPLAY 0.872340 (-3227 4350);
PAINT GREEN (-3227 4350);
DISPLAY INVISIBLE (-3227 4350);
FORCEADD TAP..1
(-3225 4150);
FORCEPROP 3 LASTPIN (-3275 4150) SIG_NAME M_L_CPU0_SB_DQ<1>
J 0
(-3265 4160);
DISPLAY 0.659574 (-3265 4160);
PAINT MONO (-3265 4160);
DISPLAY INVISIBLE (-3265 4160);
FORCEPROP 1 LASTPIN (-3275 4150) BN 1
J 0
(-3287 4158);
DISPLAY 0.489362 (-3287 4158);
PAINT GREEN (-3287 4158);
FORCEPROP 2 LAST CDS_LIB mstr_standard
J 0
(-3225 4150);
DISPLAY 0.723404 (-3225 4150);
PAINT MONO (-3225 4150);
DISPLAY INVISIBLE (-3225 4150);
FORCEPROP 1 LAST BODY_TYPE PLUMBING
J 0
(-3225 4200);
DISPLAY 0.872340 (-3225 4200);
PAINT GREEN (-3225 4200);
DISPLAY INVISIBLE (-3225 4200);
FORCEPROP 1 LAST HDL_TAP TRUE
J 0
(-2900 4025);
DISPLAY 0.872340 (-2900 4025);
DISPLAY INVISIBLE (-2900 4025);
FORCEPROP 1 LAST PATH I194
J 0
(-3227 4150);
DISPLAY 0.872340 (-3227 4150);
PAINT GREEN (-3227 4150);
DISPLAY INVISIBLE (-3227 4150);
FORCEADD TAP..1
(-3225 4200);
FORCEPROP 3 LASTPIN (-3275 4200) SIG_NAME M_L_CPU0_SB_DQ<0>
J 0
(-3265 4210);
DISPLAY 0.659574 (-3265 4210);
PAINT MONO (-3265 4210);
DISPLAY INVISIBLE (-3265 4210);
FORCEPROP 1 LASTPIN (-3275 4200) BN 0
J 0
(-3287 4208);
DISPLAY 0.489362 (-3287 4208);
PAINT GREEN (-3287 4208);
FORCEPROP 2 LAST CDS_LIB mstr_standard
J 0
(-3225 4200);
DISPLAY 0.723404 (-3225 4200);
PAINT MONO (-3225 4200);
DISPLAY INVISIBLE (-3225 4200);
FORCEPROP 1 LAST BODY_TYPE PLUMBING
J 0
(-3225 4250);
DISPLAY 0.872340 (-3225 4250);
PAINT GREEN (-3225 4250);
DISPLAY INVISIBLE (-3225 4250);
FORCEPROP 1 LAST HDL_TAP TRUE
J 0
(-2900 4075);
DISPLAY 0.872340 (-2900 4075);
DISPLAY INVISIBLE (-2900 4075);
FORCEPROP 1 LAST PATH I195
J 0
(-3227 4200);
DISPLAY 0.872340 (-3227 4200);
PAINT GREEN (-3227 4200);
DISPLAY INVISIBLE (-3227 4200);
FORCEADD TAP..1
(-3225 4100);
FORCEPROP 3 LASTPIN (-3275 4100) SIG_NAME M_L_CPU0_SB_DQ<2>
J 0
(-3265 4110);
DISPLAY 0.659574 (-3265 4110);
PAINT MONO (-3265 4110);
DISPLAY INVISIBLE (-3265 4110);
FORCEPROP 1 LASTPIN (-3275 4100) BN 2
J 0
(-3287 4108);
DISPLAY 0.489362 (-3287 4108);
PAINT GREEN (-3287 4108);
FORCEPROP 2 LAST CDS_LIB mstr_standard
J 0
(-3225 4100);
DISPLAY 0.723404 (-3225 4100);
PAINT MONO (-3225 4100);
DISPLAY INVISIBLE (-3225 4100);
FORCEPROP 1 LAST BODY_TYPE PLUMBING
J 0
(-3225 4150);
DISPLAY 0.872340 (-3225 4150);
PAINT GREEN (-3225 4150);
DISPLAY INVISIBLE (-3225 4150);
FORCEPROP 1 LAST HDL_TAP TRUE
J 0
(-2900 3975);
DISPLAY 0.872340 (-2900 3975);
DISPLAY INVISIBLE (-2900 3975);
FORCEPROP 1 LAST PATH I196
J 0
(-3227 4100);
DISPLAY 0.872340 (-3227 4100);
PAINT GREEN (-3227 4100);
DISPLAY INVISIBLE (-3227 4100);
FORCEADD OFFPAGE..6
R 2
(-2625 2450);
FORCEPROP 2 LAST $XR0 96 
J 0
(-2411 2450);
DISPLAY 0.638298 (-2411 2450);
PAINT MONO (-2411 2450);
FORCEPROP 2 LAST PATH I197
J 0
(-2400 2500);
DISPLAY 1.021277 (-2400 2500);
DISPLAY INVISIBLE (-2400 2500);
FORCEPROP 1 LAST COMMENT_BODY TRUE
J 2
(-2725 2375);
DISPLAY 0.872340 (-2725 2375);
PAINT GREEN (-2725 2375);
DISPLAY INVISIBLE (-2725 2375);
FORCEPROP 1 LAST OFFPAGE TRUE
J 2
(-2950 2325);
DISPLAY 0.872340 (-2950 2325);
PAINT GREEN (-2950 2325);
DISPLAY INVISIBLE (-2950 2325);
FORCEPROP 2 LAST CDS_LIB mstr_standard
J 2
(-2625 2450);
DISPLAY 0.723404 (-2625 2450);
PAINT MONO (-2625 2450);
DISPLAY INVISIBLE (-2625 2450);
FORCEADD TAP..1
(-3225 4050);
FORCEPROP 3 LASTPIN (-3275 4050) SIG_NAME M_L_CPU0_SB_DQ<3>
J 0
(-3265 4060);
DISPLAY 0.659574 (-3265 4060);
PAINT MONO (-3265 4060);
DISPLAY INVISIBLE (-3265 4060);
FORCEPROP 1 LASTPIN (-3275 4050) BN 3
J 0
(-3287 4058);
DISPLAY 0.489362 (-3287 4058);
PAINT GREEN (-3287 4058);
FORCEPROP 2 LAST CDS_LIB mstr_standard
J 0
(-3225 4050);
DISPLAY 0.723404 (-3225 4050);
PAINT MONO (-3225 4050);
DISPLAY INVISIBLE (-3225 4050);
FORCEPROP 1 LAST BODY_TYPE PLUMBING
J 0
(-3225 4100);
DISPLAY 0.872340 (-3225 4100);
PAINT GREEN (-3225 4100);
DISPLAY INVISIBLE (-3225 4100);
FORCEPROP 1 LAST HDL_TAP TRUE
J 0
(-2900 3925);
DISPLAY 0.872340 (-2900 3925);
DISPLAY INVISIBLE (-2900 3925);
FORCEPROP 1 LAST PATH I198
J 0
(-3227 4050);
DISPLAY 0.872340 (-3227 4050);
PAINT GREEN (-3227 4050);
DISPLAY INVISIBLE (-3227 4050);
FORCEADD TAP..1
(-3225 4000);
FORCEPROP 3 LASTPIN (-3275 4000) SIG_NAME M_L_CPU0_SB_DQ<4>
J 0
(-3265 4010);
DISPLAY 0.659574 (-3265 4010);
PAINT MONO (-3265 4010);
DISPLAY INVISIBLE (-3265 4010);
FORCEPROP 1 LASTPIN (-3275 4000) BN 4
J 0
(-3287 4008);
DISPLAY 0.489362 (-3287 4008);
PAINT GREEN (-3287 4008);
FORCEPROP 2 LAST CDS_LIB mstr_standard
J 0
(-3225 4000);
DISPLAY 0.723404 (-3225 4000);
PAINT MONO (-3225 4000);
DISPLAY INVISIBLE (-3225 4000);
FORCEPROP 1 LAST BODY_TYPE PLUMBING
J 0
(-3225 4050);
DISPLAY 0.872340 (-3225 4050);
PAINT GREEN (-3225 4050);
DISPLAY INVISIBLE (-3225 4050);
FORCEPROP 1 LAST HDL_TAP TRUE
J 0
(-2900 3875);
DISPLAY 0.872340 (-2900 3875);
DISPLAY INVISIBLE (-2900 3875);
FORCEPROP 1 LAST PATH I199
J 0
(-3227 4000);
DISPLAY 0.872340 (-3227 4000);
PAINT GREEN (-3227 4000);
DISPLAY INVISIBLE (-3227 4000);
FORCEADD TAP..1
(-3225 3950);
FORCEPROP 3 LASTPIN (-3275 3950) SIG_NAME M_L_CPU0_SB_DQ<5>
J 0
(-3265 3960);
DISPLAY 0.659574 (-3265 3960);
PAINT MONO (-3265 3960);
DISPLAY INVISIBLE (-3265 3960);
FORCEPROP 1 LASTPIN (-3275 3950) BN 5
J 0
(-3287 3958);
DISPLAY 0.489362 (-3287 3958);
PAINT GREEN (-3287 3958);
FORCEPROP 2 LAST CDS_LIB mstr_standard
J 0
(-3225 3950);
DISPLAY 0.723404 (-3225 3950);
PAINT MONO (-3225 3950);
DISPLAY INVISIBLE (-3225 3950);
FORCEPROP 1 LAST BODY_TYPE PLUMBING
J 0
(-3225 4000);
DISPLAY 0.872340 (-3225 4000);
PAINT GREEN (-3225 4000);
DISPLAY INVISIBLE (-3225 4000);
FORCEPROP 1 LAST HDL_TAP TRUE
J 0
(-2900 3825);
DISPLAY 0.872340 (-2900 3825);
DISPLAY INVISIBLE (-2900 3825);
FORCEPROP 1 LAST PATH I200
J 0
(-3227 3950);
DISPLAY 0.872340 (-3227 3950);
PAINT GREEN (-3227 3950);
DISPLAY INVISIBLE (-3227 3950);
FORCEADD TAP..1
(-3225 3900);
FORCEPROP 3 LASTPIN (-3275 3900) SIG_NAME M_L_CPU0_SB_DQ<6>
J 0
(-3265 3910);
DISPLAY 0.659574 (-3265 3910);
PAINT MONO (-3265 3910);
DISPLAY INVISIBLE (-3265 3910);
FORCEPROP 1 LASTPIN (-3275 3900) BN 6
J 0
(-3287 3908);
DISPLAY 0.489362 (-3287 3908);
PAINT GREEN (-3287 3908);
FORCEPROP 2 LAST CDS_LIB mstr_standard
J 0
(-3225 3900);
DISPLAY 0.723404 (-3225 3900);
PAINT MONO (-3225 3900);
DISPLAY INVISIBLE (-3225 3900);
FORCEPROP 1 LAST BODY_TYPE PLUMBING
J 0
(-3225 3950);
DISPLAY 0.872340 (-3225 3950);
PAINT GREEN (-3225 3950);
DISPLAY INVISIBLE (-3225 3950);
FORCEPROP 1 LAST HDL_TAP TRUE
J 0
(-2900 3775);
DISPLAY 0.872340 (-2900 3775);
DISPLAY INVISIBLE (-2900 3775);
FORCEPROP 1 LAST PATH I201
J 0
(-3227 3900);
DISPLAY 0.872340 (-3227 3900);
PAINT GREEN (-3227 3900);
DISPLAY INVISIBLE (-3227 3900);
FORCEADD TAP..1
(-3225 3850);
FORCEPROP 3 LASTPIN (-3275 3850) SIG_NAME M_L_CPU0_SB_DQ<7>
J 0
(-3265 3860);
DISPLAY 0.659574 (-3265 3860);
PAINT MONO (-3265 3860);
DISPLAY INVISIBLE (-3265 3860);
FORCEPROP 1 LASTPIN (-3275 3850) BN 7
J 0
(-3287 3858);
DISPLAY 0.489362 (-3287 3858);
PAINT GREEN (-3287 3858);
FORCEPROP 2 LAST CDS_LIB mstr_standard
J 0
(-3225 3850);
DISPLAY 0.723404 (-3225 3850);
PAINT MONO (-3225 3850);
DISPLAY INVISIBLE (-3225 3850);
FORCEPROP 1 LAST BODY_TYPE PLUMBING
J 0
(-3225 3900);
DISPLAY 0.872340 (-3225 3900);
PAINT GREEN (-3225 3900);
DISPLAY INVISIBLE (-3225 3900);
FORCEPROP 1 LAST HDL_TAP TRUE
J 0
(-2900 3725);
DISPLAY 0.872340 (-2900 3725);
DISPLAY INVISIBLE (-2900 3725);
FORCEPROP 1 LAST PATH I202
J 0
(-3227 3850);
DISPLAY 0.872340 (-3227 3850);
PAINT GREEN (-3227 3850);
DISPLAY INVISIBLE (-3227 3850);
FORCEADD TAP..1
(-3225 3650);
FORCEPROP 3 LASTPIN (-3275 3650) SIG_NAME M_L_CPU0_SB_DQ<10>
J 0
(-3265 3660);
DISPLAY 0.659574 (-3265 3660);
PAINT MONO (-3265 3660);
DISPLAY INVISIBLE (-3265 3660);
FORCEPROP 1 LASTPIN (-3275 3650) BN 10
J 0
(-3287 3658);
DISPLAY 0.489362 (-3287 3658);
PAINT GREEN (-3287 3658);
FORCEPROP 2 LAST CDS_LIB mstr_standard
J 0
(-3225 3650);
DISPLAY 0.723404 (-3225 3650);
PAINT MONO (-3225 3650);
DISPLAY INVISIBLE (-3225 3650);
FORCEPROP 1 LAST BODY_TYPE PLUMBING
J 0
(-3225 3700);
DISPLAY 0.872340 (-3225 3700);
PAINT GREEN (-3225 3700);
DISPLAY INVISIBLE (-3225 3700);
FORCEPROP 1 LAST HDL_TAP TRUE
J 0
(-2900 3525);
DISPLAY 0.872340 (-2900 3525);
DISPLAY INVISIBLE (-2900 3525);
FORCEPROP 1 LAST PATH I203
J 0
(-3227 3650);
DISPLAY 0.872340 (-3227 3650);
PAINT GREEN (-3227 3650);
DISPLAY INVISIBLE (-3227 3650);
FORCEADD TAP..1
(-3225 3700);
FORCEPROP 3 LASTPIN (-3275 3700) SIG_NAME M_L_CPU0_SB_DQ<9>
J 0
(-3265 3710);
DISPLAY 0.659574 (-3265 3710);
PAINT MONO (-3265 3710);
DISPLAY INVISIBLE (-3265 3710);
FORCEPROP 1 LASTPIN (-3275 3700) BN 9
J 0
(-3287 3708);
DISPLAY 0.489362 (-3287 3708);
PAINT GREEN (-3287 3708);
FORCEPROP 2 LAST CDS_LIB mstr_standard
J 0
(-3225 3700);
DISPLAY 0.723404 (-3225 3700);
PAINT MONO (-3225 3700);
DISPLAY INVISIBLE (-3225 3700);
FORCEPROP 1 LAST BODY_TYPE PLUMBING
J 0
(-3225 3750);
DISPLAY 0.872340 (-3225 3750);
PAINT GREEN (-3225 3750);
DISPLAY INVISIBLE (-3225 3750);
FORCEPROP 1 LAST HDL_TAP TRUE
J 0
(-2900 3575);
DISPLAY 0.872340 (-2900 3575);
DISPLAY INVISIBLE (-2900 3575);
FORCEPROP 1 LAST PATH I204
J 0
(-3227 3700);
DISPLAY 0.872340 (-3227 3700);
PAINT GREEN (-3227 3700);
DISPLAY INVISIBLE (-3227 3700);
FORCEADD TAP..1
(-3225 3750);
FORCEPROP 3 LASTPIN (-3275 3750) SIG_NAME M_L_CPU0_SB_DQ<8>
J 0
(-3265 3760);
DISPLAY 0.659574 (-3265 3760);
PAINT MONO (-3265 3760);
DISPLAY INVISIBLE (-3265 3760);
FORCEPROP 1 LASTPIN (-3275 3750) BN 8
J 0
(-3287 3758);
DISPLAY 0.489362 (-3287 3758);
PAINT GREEN (-3287 3758);
FORCEPROP 2 LAST CDS_LIB mstr_standard
J 0
(-3225 3750);
DISPLAY 0.723404 (-3225 3750);
PAINT MONO (-3225 3750);
DISPLAY INVISIBLE (-3225 3750);
FORCEPROP 1 LAST BODY_TYPE PLUMBING
J 0
(-3225 3800);
DISPLAY 0.872340 (-3225 3800);
PAINT GREEN (-3225 3800);
DISPLAY INVISIBLE (-3225 3800);
FORCEPROP 1 LAST HDL_TAP TRUE
J 0
(-2900 3625);
DISPLAY 0.872340 (-2900 3625);
DISPLAY INVISIBLE (-2900 3625);
FORCEPROP 1 LAST PATH I205
J 0
(-3227 3750);
DISPLAY 0.872340 (-3227 3750);
PAINT GREEN (-3227 3750);
DISPLAY INVISIBLE (-3227 3750);
FORCEADD TAP..1
(-3225 3600);
FORCEPROP 3 LASTPIN (-3275 3600) SIG_NAME M_L_CPU0_SB_DQ<11>
J 0
(-3265 3610);
DISPLAY 0.659574 (-3265 3610);
PAINT MONO (-3265 3610);
DISPLAY INVISIBLE (-3265 3610);
FORCEPROP 1 LASTPIN (-3275 3600) BN 11
J 0
(-3287 3608);
DISPLAY 0.489362 (-3287 3608);
PAINT GREEN (-3287 3608);
FORCEPROP 2 LAST CDS_LIB mstr_standard
J 0
(-3225 3600);
DISPLAY 0.723404 (-3225 3600);
PAINT MONO (-3225 3600);
DISPLAY INVISIBLE (-3225 3600);
FORCEPROP 1 LAST BODY_TYPE PLUMBING
J 0
(-3225 3650);
DISPLAY 0.872340 (-3225 3650);
PAINT GREEN (-3225 3650);
DISPLAY INVISIBLE (-3225 3650);
FORCEPROP 1 LAST HDL_TAP TRUE
J 0
(-2900 3475);
DISPLAY 0.872340 (-2900 3475);
DISPLAY INVISIBLE (-2900 3475);
FORCEPROP 1 LAST PATH I206
J 0
(-3227 3600);
DISPLAY 0.872340 (-3227 3600);
PAINT GREEN (-3227 3600);
DISPLAY INVISIBLE (-3227 3600);
FORCEADD TAP..1
(-3225 3550);
FORCEPROP 3 LASTPIN (-3275 3550) SIG_NAME M_L_CPU0_SB_DQ<12>
J 0
(-3265 3560);
DISPLAY 0.659574 (-3265 3560);
PAINT MONO (-3265 3560);
DISPLAY INVISIBLE (-3265 3560);
FORCEPROP 1 LASTPIN (-3275 3550) BN 12
J 0
(-3287 3558);
DISPLAY 0.489362 (-3287 3558);
PAINT GREEN (-3287 3558);
FORCEPROP 2 LAST CDS_LIB mstr_standard
J 0
(-3225 3550);
DISPLAY 0.723404 (-3225 3550);
PAINT MONO (-3225 3550);
DISPLAY INVISIBLE (-3225 3550);
FORCEPROP 1 LAST BODY_TYPE PLUMBING
J 0
(-3225 3600);
DISPLAY 0.872340 (-3225 3600);
PAINT GREEN (-3225 3600);
DISPLAY INVISIBLE (-3225 3600);
FORCEPROP 1 LAST HDL_TAP TRUE
J 0
(-2900 3425);
DISPLAY 0.872340 (-2900 3425);
DISPLAY INVISIBLE (-2900 3425);
FORCEPROP 1 LAST PATH I207
J 0
(-3227 3550);
DISPLAY 0.872340 (-3227 3550);
PAINT GREEN (-3227 3550);
DISPLAY INVISIBLE (-3227 3550);
FORCEADD TAP..1
(-3225 3450);
FORCEPROP 3 LASTPIN (-3275 3450) SIG_NAME M_L_CPU0_SB_DQ<14>
J 0
(-3265 3460);
DISPLAY 0.659574 (-3265 3460);
PAINT MONO (-3265 3460);
DISPLAY INVISIBLE (-3265 3460);
FORCEPROP 1 LASTPIN (-3275 3450) BN 14
J 0
(-3287 3458);
DISPLAY 0.489362 (-3287 3458);
PAINT GREEN (-3287 3458);
FORCEPROP 2 LAST CDS_LIB mstr_standard
J 0
(-3225 3450);
DISPLAY 0.723404 (-3225 3450);
PAINT MONO (-3225 3450);
DISPLAY INVISIBLE (-3225 3450);
FORCEPROP 1 LAST BODY_TYPE PLUMBING
J 0
(-3225 3500);
DISPLAY 0.872340 (-3225 3500);
PAINT GREEN (-3225 3500);
DISPLAY INVISIBLE (-3225 3500);
FORCEPROP 1 LAST HDL_TAP TRUE
J 0
(-2900 3325);
DISPLAY 0.872340 (-2900 3325);
DISPLAY INVISIBLE (-2900 3325);
FORCEPROP 1 LAST PATH I208
J 0
(-3227 3450);
DISPLAY 0.872340 (-3227 3450);
PAINT GREEN (-3227 3450);
DISPLAY INVISIBLE (-3227 3450);
FORCEADD TAP..1
(-3225 3400);
FORCEPROP 3 LASTPIN (-3275 3400) SIG_NAME M_L_CPU0_SB_DQ<15>
J 0
(-3265 3410);
DISPLAY 0.659574 (-3265 3410);
PAINT MONO (-3265 3410);
DISPLAY INVISIBLE (-3265 3410);
FORCEPROP 1 LASTPIN (-3275 3400) BN 15
J 0
(-3287 3408);
DISPLAY 0.489362 (-3287 3408);
PAINT GREEN (-3287 3408);
FORCEPROP 2 LAST CDS_LIB mstr_standard
J 0
(-3225 3400);
DISPLAY 0.723404 (-3225 3400);
PAINT MONO (-3225 3400);
DISPLAY INVISIBLE (-3225 3400);
FORCEPROP 1 LAST BODY_TYPE PLUMBING
J 0
(-3225 3450);
DISPLAY 0.872340 (-3225 3450);
PAINT GREEN (-3225 3450);
DISPLAY INVISIBLE (-3225 3450);
FORCEPROP 1 LAST HDL_TAP TRUE
J 0
(-2900 3275);
DISPLAY 0.872340 (-2900 3275);
DISPLAY INVISIBLE (-2900 3275);
FORCEPROP 1 LAST PATH I209
J 0
(-3227 3400);
DISPLAY 0.872340 (-3227 3400);
PAINT GREEN (-3227 3400);
DISPLAY INVISIBLE (-3227 3400);
FORCEADD TAP..1
(-3225 3500);
FORCEPROP 3 LASTPIN (-3275 3500) SIG_NAME M_L_CPU0_SB_DQ<13>
J 0
(-3265 3510);
DISPLAY 0.659574 (-3265 3510);
PAINT MONO (-3265 3510);
DISPLAY INVISIBLE (-3265 3510);
FORCEPROP 1 LASTPIN (-3275 3500) BN 13
J 0
(-3287 3508);
DISPLAY 0.489362 (-3287 3508);
PAINT GREEN (-3287 3508);
FORCEPROP 2 LAST CDS_LIB mstr_standard
J 0
(-3225 3500);
DISPLAY 0.723404 (-3225 3500);
PAINT MONO (-3225 3500);
DISPLAY INVISIBLE (-3225 3500);
FORCEPROP 1 LAST BODY_TYPE PLUMBING
J 0
(-3225 3550);
DISPLAY 0.872340 (-3225 3550);
PAINT GREEN (-3225 3550);
DISPLAY INVISIBLE (-3225 3550);
FORCEPROP 1 LAST HDL_TAP TRUE
J 0
(-2900 3375);
DISPLAY 0.872340 (-2900 3375);
DISPLAY INVISIBLE (-2900 3375);
FORCEPROP 1 LAST PATH I210
J 0
(-3227 3500);
DISPLAY 0.872340 (-3227 3500);
PAINT GREEN (-3227 3500);
DISPLAY INVISIBLE (-3227 3500);
FORCEADD TAP..1
(-3225 3300);
FORCEPROP 3 LASTPIN (-3275 3300) SIG_NAME M_L_CPU0_SB_DQ<16>
J 0
(-3265 3310);
DISPLAY 0.659574 (-3265 3310);
PAINT MONO (-3265 3310);
DISPLAY INVISIBLE (-3265 3310);
FORCEPROP 1 LASTPIN (-3275 3300) BN 16
J 0
(-3287 3308);
DISPLAY 0.489362 (-3287 3308);
PAINT GREEN (-3287 3308);
FORCEPROP 2 LAST CDS_LIB mstr_standard
J 0
(-3225 3300);
DISPLAY 0.723404 (-3225 3300);
PAINT MONO (-3225 3300);
DISPLAY INVISIBLE (-3225 3300);
FORCEPROP 1 LAST BODY_TYPE PLUMBING
J 0
(-3225 3350);
DISPLAY 0.872340 (-3225 3350);
PAINT GREEN (-3225 3350);
DISPLAY INVISIBLE (-3225 3350);
FORCEPROP 1 LAST HDL_TAP TRUE
J 0
(-2900 3175);
DISPLAY 0.872340 (-2900 3175);
DISPLAY INVISIBLE (-2900 3175);
FORCEPROP 1 LAST PATH I211
J 0
(-3227 3300);
DISPLAY 0.872340 (-3227 3300);
PAINT GREEN (-3227 3300);
DISPLAY INVISIBLE (-3227 3300);
FORCEADD TAP..1
(-3225 3250);
FORCEPROP 3 LASTPIN (-3275 3250) SIG_NAME M_L_CPU0_SB_DQ<17>
J 0
(-3265 3260);
DISPLAY 0.659574 (-3265 3260);
PAINT MONO (-3265 3260);
DISPLAY INVISIBLE (-3265 3260);
FORCEPROP 1 LASTPIN (-3275 3250) BN 17
J 0
(-3287 3258);
DISPLAY 0.489362 (-3287 3258);
PAINT GREEN (-3287 3258);
FORCEPROP 2 LAST CDS_LIB mstr_standard
J 0
(-3225 3250);
DISPLAY 0.723404 (-3225 3250);
PAINT MONO (-3225 3250);
DISPLAY INVISIBLE (-3225 3250);
FORCEPROP 1 LAST BODY_TYPE PLUMBING
J 0
(-3225 3300);
DISPLAY 0.872340 (-3225 3300);
PAINT GREEN (-3225 3300);
DISPLAY INVISIBLE (-3225 3300);
FORCEPROP 1 LAST HDL_TAP TRUE
J 0
(-2900 3125);
DISPLAY 0.872340 (-2900 3125);
DISPLAY INVISIBLE (-2900 3125);
FORCEPROP 1 LAST PATH I212
J 0
(-3227 3250);
DISPLAY 0.872340 (-3227 3250);
PAINT GREEN (-3227 3250);
DISPLAY INVISIBLE (-3227 3250);
FORCEADD TAP..1
(-3225 3200);
FORCEPROP 3 LASTPIN (-3275 3200) SIG_NAME M_L_CPU0_SB_DQ<18>
J 0
(-3265 3210);
DISPLAY 0.659574 (-3265 3210);
PAINT MONO (-3265 3210);
DISPLAY INVISIBLE (-3265 3210);
FORCEPROP 1 LASTPIN (-3275 3200) BN 18
J 0
(-3287 3208);
DISPLAY 0.489362 (-3287 3208);
PAINT GREEN (-3287 3208);
FORCEPROP 2 LAST CDS_LIB mstr_standard
J 0
(-3225 3200);
DISPLAY 0.723404 (-3225 3200);
PAINT MONO (-3225 3200);
DISPLAY INVISIBLE (-3225 3200);
FORCEPROP 1 LAST BODY_TYPE PLUMBING
J 0
(-3225 3250);
DISPLAY 0.872340 (-3225 3250);
PAINT GREEN (-3225 3250);
DISPLAY INVISIBLE (-3225 3250);
FORCEPROP 1 LAST HDL_TAP TRUE
J 0
(-2900 3075);
DISPLAY 0.872340 (-2900 3075);
DISPLAY INVISIBLE (-2900 3075);
FORCEPROP 1 LAST PATH I213
J 0
(-3227 3200);
DISPLAY 0.872340 (-3227 3200);
PAINT GREEN (-3227 3200);
DISPLAY INVISIBLE (-3227 3200);
FORCEADD TAP..1
(-3225 3150);
FORCEPROP 3 LASTPIN (-3275 3150) SIG_NAME M_L_CPU0_SB_DQ<19>
J 0
(-3265 3160);
DISPLAY 0.659574 (-3265 3160);
PAINT MONO (-3265 3160);
DISPLAY INVISIBLE (-3265 3160);
FORCEPROP 1 LASTPIN (-3275 3150) BN 19
J 0
(-3287 3158);
DISPLAY 0.489362 (-3287 3158);
PAINT GREEN (-3287 3158);
FORCEPROP 2 LAST CDS_LIB mstr_standard
J 0
(-3225 3150);
DISPLAY 0.723404 (-3225 3150);
PAINT MONO (-3225 3150);
DISPLAY INVISIBLE (-3225 3150);
FORCEPROP 1 LAST BODY_TYPE PLUMBING
J 0
(-3225 3200);
DISPLAY 0.872340 (-3225 3200);
PAINT GREEN (-3225 3200);
DISPLAY INVISIBLE (-3225 3200);
FORCEPROP 1 LAST HDL_TAP TRUE
J 0
(-2900 3025);
DISPLAY 0.872340 (-2900 3025);
DISPLAY INVISIBLE (-2900 3025);
FORCEPROP 1 LAST PATH I214
J 0
(-3227 3150);
DISPLAY 0.872340 (-3227 3150);
PAINT GREEN (-3227 3150);
DISPLAY INVISIBLE (-3227 3150);
FORCEADD TAP..1
(-3225 3100);
FORCEPROP 3 LASTPIN (-3275 3100) SIG_NAME M_L_CPU0_SB_DQ<20>
J 0
(-3265 3110);
DISPLAY 0.659574 (-3265 3110);
PAINT MONO (-3265 3110);
DISPLAY INVISIBLE (-3265 3110);
FORCEPROP 1 LASTPIN (-3275 3100) BN 20
J 0
(-3287 3108);
DISPLAY 0.489362 (-3287 3108);
PAINT GREEN (-3287 3108);
FORCEPROP 2 LAST CDS_LIB mstr_standard
J 0
(-3225 3100);
DISPLAY 0.723404 (-3225 3100);
PAINT MONO (-3225 3100);
DISPLAY INVISIBLE (-3225 3100);
FORCEPROP 1 LAST BODY_TYPE PLUMBING
J 0
(-3225 3150);
DISPLAY 0.872340 (-3225 3150);
PAINT GREEN (-3225 3150);
DISPLAY INVISIBLE (-3225 3150);
FORCEPROP 1 LAST HDL_TAP TRUE
J 0
(-2900 2975);
DISPLAY 0.872340 (-2900 2975);
DISPLAY INVISIBLE (-2900 2975);
FORCEPROP 1 LAST PATH I215
J 0
(-3227 3100);
DISPLAY 0.872340 (-3227 3100);
PAINT GREEN (-3227 3100);
DISPLAY INVISIBLE (-3227 3100);
FORCEADD TAP..1
(-3225 2850);
FORCEPROP 3 LASTPIN (-3275 2850) SIG_NAME M_L_CPU0_SB_DQ<24>
J 0
(-3265 2860);
DISPLAY 0.659574 (-3265 2860);
PAINT MONO (-3265 2860);
DISPLAY INVISIBLE (-3265 2860);
FORCEPROP 1 LASTPIN (-3275 2850) BN 24
J 0
(-3287 2858);
DISPLAY 0.489362 (-3287 2858);
PAINT GREEN (-3287 2858);
FORCEPROP 2 LAST CDS_LIB mstr_standard
J 0
(-3225 2850);
DISPLAY 0.723404 (-3225 2850);
PAINT MONO (-3225 2850);
DISPLAY INVISIBLE (-3225 2850);
FORCEPROP 1 LAST BODY_TYPE PLUMBING
J 0
(-3225 2900);
DISPLAY 0.872340 (-3225 2900);
PAINT GREEN (-3225 2900);
DISPLAY INVISIBLE (-3225 2900);
FORCEPROP 1 LAST HDL_TAP TRUE
J 0
(-2900 2725);
DISPLAY 0.872340 (-2900 2725);
DISPLAY INVISIBLE (-2900 2725);
FORCEPROP 1 LAST PATH I216
J 0
(-3227 2850);
DISPLAY 0.872340 (-3227 2850);
PAINT GREEN (-3227 2850);
DISPLAY INVISIBLE (-3227 2850);
FORCEADD TAP..1
(-3225 3050);
FORCEPROP 3 LASTPIN (-3275 3050) SIG_NAME M_L_CPU0_SB_DQ<21>
J 0
(-3265 3060);
DISPLAY 0.659574 (-3265 3060);
PAINT MONO (-3265 3060);
DISPLAY INVISIBLE (-3265 3060);
FORCEPROP 1 LASTPIN (-3275 3050) BN 21
J 0
(-3287 3058);
DISPLAY 0.489362 (-3287 3058);
PAINT GREEN (-3287 3058);
FORCEPROP 2 LAST CDS_LIB mstr_standard
J 0
(-3225 3050);
DISPLAY 0.723404 (-3225 3050);
PAINT MONO (-3225 3050);
DISPLAY INVISIBLE (-3225 3050);
FORCEPROP 1 LAST BODY_TYPE PLUMBING
J 0
(-3225 3100);
DISPLAY 0.872340 (-3225 3100);
PAINT GREEN (-3225 3100);
DISPLAY INVISIBLE (-3225 3100);
FORCEPROP 1 LAST HDL_TAP TRUE
J 0
(-2900 2925);
DISPLAY 0.872340 (-2900 2925);
DISPLAY INVISIBLE (-2900 2925);
FORCEPROP 1 LAST PATH I217
J 0
(-3227 3050);
DISPLAY 0.872340 (-3227 3050);
PAINT GREEN (-3227 3050);
DISPLAY INVISIBLE (-3227 3050);
FORCEADD TAP..1
(-3225 3000);
FORCEPROP 3 LASTPIN (-3275 3000) SIG_NAME M_L_CPU0_SB_DQ<22>
J 0
(-3265 3010);
DISPLAY 0.659574 (-3265 3010);
PAINT MONO (-3265 3010);
DISPLAY INVISIBLE (-3265 3010);
FORCEPROP 1 LASTPIN (-3275 3000) BN 22
J 0
(-3287 3008);
DISPLAY 0.489362 (-3287 3008);
PAINT GREEN (-3287 3008);
FORCEPROP 2 LAST CDS_LIB mstr_standard
J 0
(-3225 3000);
DISPLAY 0.723404 (-3225 3000);
PAINT MONO (-3225 3000);
DISPLAY INVISIBLE (-3225 3000);
FORCEPROP 1 LAST BODY_TYPE PLUMBING
J 0
(-3225 3050);
DISPLAY 0.872340 (-3225 3050);
PAINT GREEN (-3225 3050);
DISPLAY INVISIBLE (-3225 3050);
FORCEPROP 1 LAST HDL_TAP TRUE
J 0
(-2900 2875);
DISPLAY 0.872340 (-2900 2875);
DISPLAY INVISIBLE (-2900 2875);
FORCEPROP 1 LAST PATH I218
J 0
(-3227 3000);
DISPLAY 0.872340 (-3227 3000);
PAINT GREEN (-3227 3000);
DISPLAY INVISIBLE (-3227 3000);
FORCEADD TAP..1
(-3225 2950);
FORCEPROP 3 LASTPIN (-3275 2950) SIG_NAME M_L_CPU0_SB_DQ<23>
J 0
(-3265 2960);
DISPLAY 0.659574 (-3265 2960);
PAINT MONO (-3265 2960);
DISPLAY INVISIBLE (-3265 2960);
FORCEPROP 1 LASTPIN (-3275 2950) BN 23
J 0
(-3287 2958);
DISPLAY 0.489362 (-3287 2958);
PAINT GREEN (-3287 2958);
FORCEPROP 2 LAST CDS_LIB mstr_standard
J 0
(-3225 2950);
DISPLAY 0.723404 (-3225 2950);
PAINT MONO (-3225 2950);
DISPLAY INVISIBLE (-3225 2950);
FORCEPROP 1 LAST BODY_TYPE PLUMBING
J 0
(-3225 3000);
DISPLAY 0.872340 (-3225 3000);
PAINT GREEN (-3225 3000);
DISPLAY INVISIBLE (-3225 3000);
FORCEPROP 1 LAST HDL_TAP TRUE
J 0
(-2900 2825);
DISPLAY 0.872340 (-2900 2825);
DISPLAY INVISIBLE (-2900 2825);
FORCEPROP 1 LAST PATH I219
J 0
(-3227 2950);
DISPLAY 0.872340 (-3227 2950);
PAINT GREEN (-3227 2950);
DISPLAY INVISIBLE (-3227 2950);
FORCEADD TAP..1
(-3225 2800);
FORCEPROP 3 LASTPIN (-3275 2800) SIG_NAME M_L_CPU0_SB_DQ<25>
J 0
(-3265 2810);
DISPLAY 0.659574 (-3265 2810);
PAINT MONO (-3265 2810);
DISPLAY INVISIBLE (-3265 2810);
FORCEPROP 1 LASTPIN (-3275 2800) BN 25
J 0
(-3287 2808);
DISPLAY 0.489362 (-3287 2808);
PAINT GREEN (-3287 2808);
FORCEPROP 2 LAST CDS_LIB mstr_standard
J 0
(-3225 2800);
DISPLAY 0.723404 (-3225 2800);
PAINT MONO (-3225 2800);
DISPLAY INVISIBLE (-3225 2800);
FORCEPROP 1 LAST BODY_TYPE PLUMBING
J 0
(-3225 2850);
DISPLAY 0.872340 (-3225 2850);
PAINT GREEN (-3225 2850);
DISPLAY INVISIBLE (-3225 2850);
FORCEPROP 1 LAST HDL_TAP TRUE
J 0
(-2900 2675);
DISPLAY 0.872340 (-2900 2675);
DISPLAY INVISIBLE (-2900 2675);
FORCEPROP 1 LAST PATH I220
J 0
(-3227 2800);
DISPLAY 0.872340 (-3227 2800);
PAINT GREEN (-3227 2800);
DISPLAY INVISIBLE (-3227 2800);
FORCEADD TAP..1
(-3225 2750);
FORCEPROP 3 LASTPIN (-3275 2750) SIG_NAME M_L_CPU0_SB_DQ<26>
J 0
(-3265 2760);
DISPLAY 0.659574 (-3265 2760);
PAINT MONO (-3265 2760);
DISPLAY INVISIBLE (-3265 2760);
FORCEPROP 1 LASTPIN (-3275 2750) BN 26
J 0
(-3287 2758);
DISPLAY 0.489362 (-3287 2758);
PAINT GREEN (-3287 2758);
FORCEPROP 2 LAST CDS_LIB mstr_standard
J 0
(-3225 2750);
DISPLAY 0.723404 (-3225 2750);
PAINT MONO (-3225 2750);
DISPLAY INVISIBLE (-3225 2750);
FORCEPROP 1 LAST BODY_TYPE PLUMBING
J 0
(-3225 2800);
DISPLAY 0.872340 (-3225 2800);
PAINT GREEN (-3225 2800);
DISPLAY INVISIBLE (-3225 2800);
FORCEPROP 1 LAST HDL_TAP TRUE
J 0
(-2900 2625);
DISPLAY 0.872340 (-2900 2625);
DISPLAY INVISIBLE (-2900 2625);
FORCEPROP 1 LAST PATH I221
J 0
(-3227 2750);
DISPLAY 0.872340 (-3227 2750);
PAINT GREEN (-3227 2750);
DISPLAY INVISIBLE (-3227 2750);
FORCEADD TAP..1
(-3225 2700);
FORCEPROP 3 LASTPIN (-3275 2700) SIG_NAME M_L_CPU0_SB_DQ<27>
J 0
(-3265 2710);
DISPLAY 0.659574 (-3265 2710);
PAINT MONO (-3265 2710);
DISPLAY INVISIBLE (-3265 2710);
FORCEPROP 1 LASTPIN (-3275 2700) BN 27
J 0
(-3287 2708);
DISPLAY 0.489362 (-3287 2708);
PAINT GREEN (-3287 2708);
FORCEPROP 2 LAST CDS_LIB mstr_standard
J 0
(-3225 2700);
DISPLAY 0.723404 (-3225 2700);
PAINT MONO (-3225 2700);
DISPLAY INVISIBLE (-3225 2700);
FORCEPROP 1 LAST BODY_TYPE PLUMBING
J 0
(-3225 2750);
DISPLAY 0.872340 (-3225 2750);
PAINT GREEN (-3225 2750);
DISPLAY INVISIBLE (-3225 2750);
FORCEPROP 1 LAST HDL_TAP TRUE
J 0
(-2900 2575);
DISPLAY 0.872340 (-2900 2575);
DISPLAY INVISIBLE (-2900 2575);
FORCEPROP 1 LAST PATH I222
J 0
(-3227 2700);
DISPLAY 0.872340 (-3227 2700);
PAINT GREEN (-3227 2700);
DISPLAY INVISIBLE (-3227 2700);
FORCEADD TAP..1
(-3225 2650);
FORCEPROP 3 LASTPIN (-3275 2650) SIG_NAME M_L_CPU0_SB_DQ<28>
J 0
(-3265 2660);
DISPLAY 0.659574 (-3265 2660);
PAINT MONO (-3265 2660);
DISPLAY INVISIBLE (-3265 2660);
FORCEPROP 1 LASTPIN (-3275 2650) BN 28
J 0
(-3287 2658);
DISPLAY 0.489362 (-3287 2658);
PAINT GREEN (-3287 2658);
FORCEPROP 2 LAST CDS_LIB mstr_standard
J 0
(-3225 2650);
DISPLAY 0.723404 (-3225 2650);
PAINT MONO (-3225 2650);
DISPLAY INVISIBLE (-3225 2650);
FORCEPROP 1 LAST BODY_TYPE PLUMBING
J 0
(-3225 2700);
DISPLAY 0.872340 (-3225 2700);
PAINT GREEN (-3225 2700);
DISPLAY INVISIBLE (-3225 2700);
FORCEPROP 1 LAST HDL_TAP TRUE
J 0
(-2900 2525);
DISPLAY 0.872340 (-2900 2525);
DISPLAY INVISIBLE (-2900 2525);
FORCEPROP 1 LAST PATH I223
J 0
(-3227 2650);
DISPLAY 0.872340 (-3227 2650);
PAINT GREEN (-3227 2650);
DISPLAY INVISIBLE (-3227 2650);
FORCEADD TAP..1
(-3225 2600);
FORCEPROP 3 LASTPIN (-3275 2600) SIG_NAME M_L_CPU0_SB_DQ<29>
J 0
(-3265 2610);
DISPLAY 0.659574 (-3265 2610);
PAINT MONO (-3265 2610);
DISPLAY INVISIBLE (-3265 2610);
FORCEPROP 1 LASTPIN (-3275 2600) BN 29
J 0
(-3287 2608);
DISPLAY 0.489362 (-3287 2608);
PAINT GREEN (-3287 2608);
FORCEPROP 2 LAST CDS_LIB mstr_standard
J 0
(-3225 2600);
DISPLAY 0.723404 (-3225 2600);
PAINT MONO (-3225 2600);
DISPLAY INVISIBLE (-3225 2600);
FORCEPROP 1 LAST BODY_TYPE PLUMBING
J 0
(-3225 2650);
DISPLAY 0.872340 (-3225 2650);
PAINT GREEN (-3225 2650);
DISPLAY INVISIBLE (-3225 2650);
FORCEPROP 1 LAST HDL_TAP TRUE
J 0
(-2900 2475);
DISPLAY 0.872340 (-2900 2475);
DISPLAY INVISIBLE (-2900 2475);
FORCEPROP 1 LAST PATH I224
J 0
(-3227 2600);
DISPLAY 0.872340 (-3227 2600);
PAINT GREEN (-3227 2600);
DISPLAY INVISIBLE (-3227 2600);
FORCEADD TAP..1
(-3225 2500);
FORCEPROP 3 LASTPIN (-3275 2500) SIG_NAME M_L_CPU0_SB_DQ<31>
J 0
(-3265 2510);
DISPLAY 0.659574 (-3265 2510);
PAINT MONO (-3265 2510);
DISPLAY INVISIBLE (-3265 2510);
FORCEPROP 1 LASTPIN (-3275 2500) BN 31
J 0
(-3287 2508);
DISPLAY 0.489362 (-3287 2508);
PAINT GREEN (-3287 2508);
FORCEPROP 2 LAST CDS_LIB mstr_standard
J 0
(-3225 2500);
DISPLAY 0.723404 (-3225 2500);
PAINT MONO (-3225 2500);
DISPLAY INVISIBLE (-3225 2500);
FORCEPROP 1 LAST BODY_TYPE PLUMBING
J 0
(-3225 2550);
DISPLAY 0.872340 (-3225 2550);
PAINT GREEN (-3225 2550);
DISPLAY INVISIBLE (-3225 2550);
FORCEPROP 1 LAST HDL_TAP TRUE
J 0
(-2900 2375);
DISPLAY 0.872340 (-2900 2375);
DISPLAY INVISIBLE (-2900 2375);
FORCEPROP 1 LAST PATH I225
J 0
(-3227 2500);
DISPLAY 0.872340 (-3227 2500);
PAINT GREEN (-3227 2500);
DISPLAY INVISIBLE (-3227 2500);
FORCEADD TAP..1
(-3225 2550);
FORCEPROP 3 LASTPIN (-3275 2550) SIG_NAME M_L_CPU0_SB_DQ<30>
J 0
(-3265 2560);
DISPLAY 0.659574 (-3265 2560);
PAINT MONO (-3265 2560);
DISPLAY INVISIBLE (-3265 2560);
FORCEPROP 1 LASTPIN (-3275 2550) BN 30
J 0
(-3287 2558);
DISPLAY 0.489362 (-3287 2558);
PAINT GREEN (-3287 2558);
FORCEPROP 2 LAST CDS_LIB mstr_standard
J 0
(-3225 2550);
DISPLAY 0.723404 (-3225 2550);
PAINT MONO (-3225 2550);
DISPLAY INVISIBLE (-3225 2550);
FORCEPROP 1 LAST BODY_TYPE PLUMBING
J 0
(-3225 2600);
DISPLAY 0.872340 (-3225 2600);
PAINT GREEN (-3225 2600);
DISPLAY INVISIBLE (-3225 2600);
FORCEPROP 1 LAST HDL_TAP TRUE
J 0
(-2900 2425);
DISPLAY 0.872340 (-2900 2425);
DISPLAY INVISIBLE (-2900 2425);
FORCEPROP 1 LAST PATH I226
J 0
(-3227 2550);
DISPLAY 0.872340 (-3227 2550);
PAINT GREEN (-3227 2550);
DISPLAY INVISIBLE (-3227 2550);
FORCEADD TAP..1
(-3225 2400);
FORCEPROP 3 LASTPIN (-3275 2400) SIG_NAME M_L_CPU0_SA_CB<0>
J 0
(-3265 2410);
DISPLAY 0.659574 (-3265 2410);
PAINT MONO (-3265 2410);
DISPLAY INVISIBLE (-3265 2410);
FORCEPROP 1 LASTPIN (-3275 2400) BN 0
J 0
(-3287 2408);
DISPLAY 0.489362 (-3287 2408);
PAINT GREEN (-3287 2408);
FORCEPROP 2 LAST CDS_LIB mstr_standard
J 2
(-3225 2400);
DISPLAY 0.723404 (-3225 2400);
PAINT MONO (-3225 2400);
DISPLAY INVISIBLE (-3225 2400);
FORCEPROP 1 LAST BODY_TYPE PLUMBING
J 0
(-3225 2450);
DISPLAY 0.872340 (-3225 2450);
PAINT GREEN (-3225 2450);
DISPLAY INVISIBLE (-3225 2450);
FORCEPROP 1 LAST HDL_TAP TRUE
J 0
(-2900 2275);
DISPLAY 0.872340 (-2900 2275);
DISPLAY INVISIBLE (-2900 2275);
FORCEPROP 1 LAST PATH I227
J 0
(-3227 2400);
DISPLAY 0.872340 (-3227 2400);
PAINT GREEN (-3227 2400);
DISPLAY INVISIBLE (-3227 2400);
FORCEADD TAP..1
(-3225 2350);
FORCEPROP 3 LASTPIN (-3275 2350) SIG_NAME M_L_CPU0_SA_CB<1>
J 0
(-3265 2360);
DISPLAY 0.659574 (-3265 2360);
PAINT MONO (-3265 2360);
DISPLAY INVISIBLE (-3265 2360);
FORCEPROP 1 LASTPIN (-3275 2350) BN 1
J 0
(-3287 2358);
DISPLAY 0.489362 (-3287 2358);
PAINT GREEN (-3287 2358);
FORCEPROP 2 LAST CDS_LIB mstr_standard
J 2
(-3225 2350);
DISPLAY 0.723404 (-3225 2350);
PAINT MONO (-3225 2350);
DISPLAY INVISIBLE (-3225 2350);
FORCEPROP 1 LAST BODY_TYPE PLUMBING
J 0
(-3225 2400);
DISPLAY 0.872340 (-3225 2400);
PAINT GREEN (-3225 2400);
DISPLAY INVISIBLE (-3225 2400);
FORCEPROP 1 LAST HDL_TAP TRUE
J 0
(-2900 2225);
DISPLAY 0.872340 (-2900 2225);
DISPLAY INVISIBLE (-2900 2225);
FORCEPROP 1 LAST PATH I228
J 0
(-3227 2350);
DISPLAY 0.872340 (-3227 2350);
PAINT GREEN (-3227 2350);
DISPLAY INVISIBLE (-3227 2350);
FORCEADD TAP..1
(-3225 2300);
FORCEPROP 3 LASTPIN (-3275 2300) SIG_NAME M_L_CPU0_SA_CB<2>
J 0
(-3265 2310);
DISPLAY 0.659574 (-3265 2310);
PAINT MONO (-3265 2310);
DISPLAY INVISIBLE (-3265 2310);
FORCEPROP 1 LASTPIN (-3275 2300) BN 2
J 0
(-3287 2308);
DISPLAY 0.489362 (-3287 2308);
PAINT GREEN (-3287 2308);
FORCEPROP 2 LAST CDS_LIB mstr_standard
J 2
(-3225 2300);
DISPLAY 0.723404 (-3225 2300);
PAINT MONO (-3225 2300);
DISPLAY INVISIBLE (-3225 2300);
FORCEPROP 1 LAST BODY_TYPE PLUMBING
J 0
(-3225 2350);
DISPLAY 0.872340 (-3225 2350);
PAINT GREEN (-3225 2350);
DISPLAY INVISIBLE (-3225 2350);
FORCEPROP 1 LAST HDL_TAP TRUE
J 0
(-2900 2175);
DISPLAY 0.872340 (-2900 2175);
DISPLAY INVISIBLE (-2900 2175);
FORCEPROP 1 LAST PATH I229
J 0
(-3227 2300);
DISPLAY 0.872340 (-3227 2300);
PAINT GREEN (-3227 2300);
DISPLAY INVISIBLE (-3227 2300);
FORCEADD TAP..1
(-3225 2250);
FORCEPROP 3 LASTPIN (-3275 2250) SIG_NAME M_L_CPU0_SA_CB<3>
J 0
(-3265 2260);
DISPLAY 0.659574 (-3265 2260);
PAINT MONO (-3265 2260);
DISPLAY INVISIBLE (-3265 2260);
FORCEPROP 1 LASTPIN (-3275 2250) BN 3
J 0
(-3287 2258);
DISPLAY 0.489362 (-3287 2258);
PAINT GREEN (-3287 2258);
FORCEPROP 2 LAST CDS_LIB mstr_standard
J 2
(-3225 2250);
DISPLAY 0.723404 (-3225 2250);
PAINT MONO (-3225 2250);
DISPLAY INVISIBLE (-3225 2250);
FORCEPROP 1 LAST BODY_TYPE PLUMBING
J 0
(-3225 2300);
DISPLAY 0.872340 (-3225 2300);
PAINT GREEN (-3225 2300);
DISPLAY INVISIBLE (-3225 2300);
FORCEPROP 1 LAST HDL_TAP TRUE
J 0
(-2900 2125);
DISPLAY 0.872340 (-2900 2125);
DISPLAY INVISIBLE (-2900 2125);
FORCEPROP 1 LAST PATH I230
J 0
(-3227 2250);
DISPLAY 0.872340 (-3227 2250);
PAINT GREEN (-3227 2250);
DISPLAY INVISIBLE (-3227 2250);
FORCEADD TAP..1
(-3225 2200);
FORCEPROP 3 LASTPIN (-3275 2200) SIG_NAME M_L_CPU0_SA_CB<4>
J 0
(-3265 2210);
DISPLAY 0.659574 (-3265 2210);
PAINT MONO (-3265 2210);
DISPLAY INVISIBLE (-3265 2210);
FORCEPROP 1 LASTPIN (-3275 2200) BN 4
J 0
(-3287 2208);
DISPLAY 0.489362 (-3287 2208);
PAINT GREEN (-3287 2208);
FORCEPROP 2 LAST CDS_LIB mstr_standard
J 2
(-3225 2200);
DISPLAY 0.723404 (-3225 2200);
PAINT MONO (-3225 2200);
DISPLAY INVISIBLE (-3225 2200);
FORCEPROP 1 LAST BODY_TYPE PLUMBING
J 0
(-3225 2250);
DISPLAY 0.872340 (-3225 2250);
PAINT GREEN (-3225 2250);
DISPLAY INVISIBLE (-3225 2250);
FORCEPROP 1 LAST HDL_TAP TRUE
J 0
(-2900 2075);
DISPLAY 0.872340 (-2900 2075);
DISPLAY INVISIBLE (-2900 2075);
FORCEPROP 1 LAST PATH I231
J 0
(-3227 2200);
DISPLAY 0.872340 (-3227 2200);
PAINT GREEN (-3227 2200);
DISPLAY INVISIBLE (-3227 2200);
FORCEADD TAP..1
(-3225 2100);
FORCEPROP 3 LASTPIN (-3275 2100) SIG_NAME M_L_CPU0_SA_CB<6>
J 0
(-3265 2110);
DISPLAY 0.659574 (-3265 2110);
PAINT MONO (-3265 2110);
DISPLAY INVISIBLE (-3265 2110);
FORCEPROP 1 LASTPIN (-3275 2100) BN 6
J 0
(-3287 2108);
DISPLAY 0.489362 (-3287 2108);
PAINT GREEN (-3287 2108);
FORCEPROP 2 LAST CDS_LIB mstr_standard
J 2
(-3225 2100);
DISPLAY 0.723404 (-3225 2100);
PAINT MONO (-3225 2100);
DISPLAY INVISIBLE (-3225 2100);
FORCEPROP 1 LAST BODY_TYPE PLUMBING
J 0
(-3225 2150);
DISPLAY 0.872340 (-3225 2150);
PAINT GREEN (-3225 2150);
DISPLAY INVISIBLE (-3225 2150);
FORCEPROP 1 LAST HDL_TAP TRUE
J 0
(-2900 1975);
DISPLAY 0.872340 (-2900 1975);
DISPLAY INVISIBLE (-2900 1975);
FORCEPROP 1 LAST PATH I232
J 0
(-3227 2100);
DISPLAY 0.872340 (-3227 2100);
PAINT GREEN (-3227 2100);
DISPLAY INVISIBLE (-3227 2100);
FORCEADD TAP..1
(-3225 2150);
FORCEPROP 3 LASTPIN (-3275 2150) SIG_NAME M_L_CPU0_SA_CB<5>
J 0
(-3265 2160);
DISPLAY 0.659574 (-3265 2160);
PAINT MONO (-3265 2160);
DISPLAY INVISIBLE (-3265 2160);
FORCEPROP 1 LASTPIN (-3275 2150) BN 5
J 0
(-3287 2158);
DISPLAY 0.489362 (-3287 2158);
PAINT GREEN (-3287 2158);
FORCEPROP 2 LAST CDS_LIB mstr_standard
J 2
(-3225 2150);
DISPLAY 0.723404 (-3225 2150);
PAINT MONO (-3225 2150);
DISPLAY INVISIBLE (-3225 2150);
FORCEPROP 1 LAST BODY_TYPE PLUMBING
J 0
(-3225 2200);
DISPLAY 0.872340 (-3225 2200);
PAINT GREEN (-3225 2200);
DISPLAY INVISIBLE (-3225 2200);
FORCEPROP 1 LAST HDL_TAP TRUE
J 0
(-2900 2025);
DISPLAY 0.872340 (-2900 2025);
DISPLAY INVISIBLE (-2900 2025);
FORCEPROP 1 LAST PATH I233
J 0
(-3227 2150);
DISPLAY 0.872340 (-3227 2150);
PAINT GREEN (-3227 2150);
DISPLAY INVISIBLE (-3227 2150);
FORCEADD TAP..1
(-3225 2050);
FORCEPROP 3 LASTPIN (-3275 2050) SIG_NAME M_L_CPU0_SA_CB<7>
J 0
(-3265 2060);
DISPLAY 0.659574 (-3265 2060);
PAINT MONO (-3265 2060);
DISPLAY INVISIBLE (-3265 2060);
FORCEPROP 1 LASTPIN (-3275 2050) BN 7
J 0
(-3287 2058);
DISPLAY 0.489362 (-3287 2058);
PAINT GREEN (-3287 2058);
FORCEPROP 2 LAST CDS_LIB mstr_standard
J 2
(-3225 2050);
DISPLAY 0.723404 (-3225 2050);
PAINT MONO (-3225 2050);
DISPLAY INVISIBLE (-3225 2050);
FORCEPROP 1 LAST BODY_TYPE PLUMBING
J 0
(-3225 2100);
DISPLAY 0.872340 (-3225 2100);
PAINT GREEN (-3225 2100);
DISPLAY INVISIBLE (-3225 2100);
FORCEPROP 1 LAST HDL_TAP TRUE
J 0
(-2900 1925);
DISPLAY 0.872340 (-2900 1925);
DISPLAY INVISIBLE (-2900 1925);
FORCEPROP 1 LAST PATH I234
J 0
(-3227 2050);
DISPLAY 0.872340 (-3227 2050);
PAINT GREEN (-3227 2050);
DISPLAY INVISIBLE (-3227 2050);
FORCEADD OFFPAGE..6
R 2
(-2625 2000);
FORCEPROP 2 LAST $XR0 96 
J 0
(-2411 2000);
DISPLAY 0.638298 (-2411 2000);
PAINT MONO (-2411 2000);
FORCEPROP 2 LAST PATH I235
J 0
(-2400 2050);
DISPLAY 1.021277 (-2400 2050);
DISPLAY INVISIBLE (-2400 2050);
FORCEPROP 1 LAST COMMENT_BODY TRUE
J 2
(-2725 1925);
DISPLAY 0.872340 (-2725 1925);
PAINT GREEN (-2725 1925);
DISPLAY INVISIBLE (-2725 1925);
FORCEPROP 1 LAST OFFPAGE TRUE
J 2
(-2950 1875);
DISPLAY 0.872340 (-2950 1875);
PAINT GREEN (-2950 1875);
DISPLAY INVISIBLE (-2950 1875);
FORCEPROP 2 LAST CDS_LIB mstr_standard
J 2
(-2625 2000);
DISPLAY 0.723404 (-2625 2000);
PAINT MONO (-2625 2000);
DISPLAY INVISIBLE (-2625 2000);
FORCEADD TAP..1
(-3225 1850);
FORCEPROP 3 LASTPIN (-3275 1850) SIG_NAME M_L_CPU0_SB_CB<2>
J 0
(-3265 1860);
DISPLAY 0.659574 (-3265 1860);
PAINT MONO (-3265 1860);
DISPLAY INVISIBLE (-3265 1860);
FORCEPROP 1 LASTPIN (-3275 1850) BN 2
J 0
(-3287 1858);
DISPLAY 0.489362 (-3287 1858);
PAINT GREEN (-3287 1858);
FORCEPROP 2 LAST CDS_LIB mstr_standard
J 2
(-3225 1850);
DISPLAY 0.723404 (-3225 1850);
PAINT MONO (-3225 1850);
DISPLAY INVISIBLE (-3225 1850);
FORCEPROP 1 LAST BODY_TYPE PLUMBING
J 0
(-3225 1900);
DISPLAY 0.872340 (-3225 1900);
PAINT GREEN (-3225 1900);
DISPLAY INVISIBLE (-3225 1900);
FORCEPROP 1 LAST HDL_TAP TRUE
J 0
(-2900 1725);
DISPLAY 0.872340 (-2900 1725);
DISPLAY INVISIBLE (-2900 1725);
FORCEPROP 1 LAST PATH I236
J 0
(-3227 1850);
DISPLAY 0.872340 (-3227 1850);
PAINT GREEN (-3227 1850);
DISPLAY INVISIBLE (-3227 1850);
FORCEADD TAP..1
(-3225 1900);
FORCEPROP 3 LASTPIN (-3275 1900) SIG_NAME M_L_CPU0_SB_CB<1>
J 0
(-3265 1910);
DISPLAY 0.659574 (-3265 1910);
PAINT MONO (-3265 1910);
DISPLAY INVISIBLE (-3265 1910);
FORCEPROP 1 LASTPIN (-3275 1900) BN 1
J 0
(-3287 1908);
DISPLAY 0.489362 (-3287 1908);
PAINT GREEN (-3287 1908);
FORCEPROP 2 LAST CDS_LIB mstr_standard
J 2
(-3225 1900);
DISPLAY 0.723404 (-3225 1900);
PAINT MONO (-3225 1900);
DISPLAY INVISIBLE (-3225 1900);
FORCEPROP 1 LAST BODY_TYPE PLUMBING
J 0
(-3225 1950);
DISPLAY 0.872340 (-3225 1950);
PAINT GREEN (-3225 1950);
DISPLAY INVISIBLE (-3225 1950);
FORCEPROP 1 LAST HDL_TAP TRUE
J 0
(-2900 1775);
DISPLAY 0.872340 (-2900 1775);
DISPLAY INVISIBLE (-2900 1775);
FORCEPROP 1 LAST PATH I237
J 0
(-3227 1900);
DISPLAY 0.872340 (-3227 1900);
PAINT GREEN (-3227 1900);
DISPLAY INVISIBLE (-3227 1900);
FORCEADD TAP..1
(-3225 1950);
FORCEPROP 3 LASTPIN (-3275 1950) SIG_NAME M_L_CPU0_SB_CB<0>
J 0
(-3265 1960);
DISPLAY 0.659574 (-3265 1960);
PAINT MONO (-3265 1960);
DISPLAY INVISIBLE (-3265 1960);
FORCEPROP 1 LASTPIN (-3275 1950) BN 0
J 0
(-3287 1958);
DISPLAY 0.489362 (-3287 1958);
PAINT GREEN (-3287 1958);
FORCEPROP 2 LAST CDS_LIB mstr_standard
J 2
(-3225 1950);
DISPLAY 0.723404 (-3225 1950);
PAINT MONO (-3225 1950);
DISPLAY INVISIBLE (-3225 1950);
FORCEPROP 1 LAST BODY_TYPE PLUMBING
J 0
(-3225 2000);
DISPLAY 0.872340 (-3225 2000);
PAINT GREEN (-3225 2000);
DISPLAY INVISIBLE (-3225 2000);
FORCEPROP 1 LAST HDL_TAP TRUE
J 0
(-2900 1825);
DISPLAY 0.872340 (-2900 1825);
DISPLAY INVISIBLE (-2900 1825);
FORCEPROP 1 LAST PATH I238
J 0
(-3227 1950);
DISPLAY 0.872340 (-3227 1950);
PAINT GREEN (-3227 1950);
DISPLAY INVISIBLE (-3227 1950);
FORCEADD TAP..1
(-3225 1800);
FORCEPROP 3 LASTPIN (-3275 1800) SIG_NAME M_L_CPU0_SB_CB<3>
J 0
(-3265 1810);
DISPLAY 0.659574 (-3265 1810);
PAINT MONO (-3265 1810);
DISPLAY INVISIBLE (-3265 1810);
FORCEPROP 1 LASTPIN (-3275 1800) BN 3
J 0
(-3287 1808);
DISPLAY 0.489362 (-3287 1808);
PAINT GREEN (-3287 1808);
FORCEPROP 2 LAST CDS_LIB mstr_standard
J 2
(-3225 1800);
DISPLAY 0.723404 (-3225 1800);
PAINT MONO (-3225 1800);
DISPLAY INVISIBLE (-3225 1800);
FORCEPROP 1 LAST BODY_TYPE PLUMBING
J 0
(-3225 1850);
DISPLAY 0.872340 (-3225 1850);
PAINT GREEN (-3225 1850);
DISPLAY INVISIBLE (-3225 1850);
FORCEPROP 1 LAST HDL_TAP TRUE
J 0
(-2900 1675);
DISPLAY 0.872340 (-2900 1675);
DISPLAY INVISIBLE (-2900 1675);
FORCEPROP 1 LAST PATH I239
J 0
(-3227 1800);
DISPLAY 0.872340 (-3227 1800);
PAINT GREEN (-3227 1800);
DISPLAY INVISIBLE (-3227 1800);
FORCEADD TAP..1
(-3225 1750);
FORCEPROP 3 LASTPIN (-3275 1750) SIG_NAME M_L_CPU0_SB_CB<4>
J 0
(-3265 1760);
DISPLAY 0.659574 (-3265 1760);
PAINT MONO (-3265 1760);
DISPLAY INVISIBLE (-3265 1760);
FORCEPROP 1 LASTPIN (-3275 1750) BN 4
J 0
(-3287 1758);
DISPLAY 0.489362 (-3287 1758);
PAINT GREEN (-3287 1758);
FORCEPROP 2 LAST CDS_LIB mstr_standard
J 2
(-3225 1750);
DISPLAY 0.723404 (-3225 1750);
PAINT MONO (-3225 1750);
DISPLAY INVISIBLE (-3225 1750);
FORCEPROP 1 LAST BODY_TYPE PLUMBING
J 0
(-3225 1800);
DISPLAY 0.872340 (-3225 1800);
PAINT GREEN (-3225 1800);
DISPLAY INVISIBLE (-3225 1800);
FORCEPROP 1 LAST HDL_TAP TRUE
J 0
(-2900 1625);
DISPLAY 0.872340 (-2900 1625);
DISPLAY INVISIBLE (-2900 1625);
FORCEPROP 1 LAST PATH I240
J 0
(-3227 1750);
DISPLAY 0.872340 (-3227 1750);
PAINT GREEN (-3227 1750);
DISPLAY INVISIBLE (-3227 1750);
FORCEADD TAP..1
(-3225 1600);
FORCEPROP 3 LASTPIN (-3275 1600) SIG_NAME M_L_CPU0_SB_CB<7>
J 0
(-3265 1610);
DISPLAY 0.659574 (-3265 1610);
PAINT MONO (-3265 1610);
DISPLAY INVISIBLE (-3265 1610);
FORCEPROP 1 LASTPIN (-3275 1600) BN 7
J 0
(-3287 1608);
DISPLAY 0.489362 (-3287 1608);
PAINT GREEN (-3287 1608);
FORCEPROP 2 LAST CDS_LIB mstr_standard
J 2
(-3225 1600);
DISPLAY 0.723404 (-3225 1600);
PAINT MONO (-3225 1600);
DISPLAY INVISIBLE (-3225 1600);
FORCEPROP 1 LAST BODY_TYPE PLUMBING
J 0
(-3225 1650);
DISPLAY 0.872340 (-3225 1650);
PAINT GREEN (-3225 1650);
DISPLAY INVISIBLE (-3225 1650);
FORCEPROP 1 LAST HDL_TAP TRUE
J 0
(-2900 1475);
DISPLAY 0.872340 (-2900 1475);
DISPLAY INVISIBLE (-2900 1475);
FORCEPROP 1 LAST PATH I241
J 0
(-3227 1600);
DISPLAY 0.872340 (-3227 1600);
PAINT GREEN (-3227 1600);
DISPLAY INVISIBLE (-3227 1600);
FORCEADD TAP..1
(-3225 1650);
FORCEPROP 3 LASTPIN (-3275 1650) SIG_NAME M_L_CPU0_SB_CB<6>
J 0
(-3265 1660);
DISPLAY 0.659574 (-3265 1660);
PAINT MONO (-3265 1660);
DISPLAY INVISIBLE (-3265 1660);
FORCEPROP 1 LASTPIN (-3275 1650) BN 6
J 0
(-3287 1658);
DISPLAY 0.489362 (-3287 1658);
PAINT GREEN (-3287 1658);
FORCEPROP 2 LAST CDS_LIB mstr_standard
J 2
(-3225 1650);
DISPLAY 0.723404 (-3225 1650);
PAINT MONO (-3225 1650);
DISPLAY INVISIBLE (-3225 1650);
FORCEPROP 1 LAST BODY_TYPE PLUMBING
J 0
(-3225 1700);
DISPLAY 0.872340 (-3225 1700);
PAINT GREEN (-3225 1700);
DISPLAY INVISIBLE (-3225 1700);
FORCEPROP 1 LAST HDL_TAP TRUE
J 0
(-2900 1525);
DISPLAY 0.872340 (-2900 1525);
DISPLAY INVISIBLE (-2900 1525);
FORCEPROP 1 LAST PATH I242
J 0
(-3227 1650);
DISPLAY 0.872340 (-3227 1650);
PAINT GREEN (-3227 1650);
DISPLAY INVISIBLE (-3227 1650);
FORCEADD TAP..1
(-3225 1700);
FORCEPROP 3 LASTPIN (-3275 1700) SIG_NAME M_L_CPU0_SB_CB<5>
J 0
(-3265 1710);
DISPLAY 0.659574 (-3265 1710);
PAINT MONO (-3265 1710);
DISPLAY INVISIBLE (-3265 1710);
FORCEPROP 1 LASTPIN (-3275 1700) BN 5
J 0
(-3287 1708);
DISPLAY 0.489362 (-3287 1708);
PAINT GREEN (-3287 1708);
FORCEPROP 2 LAST CDS_LIB mstr_standard
J 2
(-3225 1700);
DISPLAY 0.723404 (-3225 1700);
PAINT MONO (-3225 1700);
DISPLAY INVISIBLE (-3225 1700);
FORCEPROP 1 LAST BODY_TYPE PLUMBING
J 0
(-3225 1750);
DISPLAY 0.872340 (-3225 1750);
PAINT GREEN (-3225 1750);
DISPLAY INVISIBLE (-3225 1750);
FORCEPROP 1 LAST HDL_TAP TRUE
J 0
(-2900 1575);
DISPLAY 0.872340 (-2900 1575);
DISPLAY INVISIBLE (-2900 1575);
FORCEPROP 1 LAST PATH I243
J 0
(-3227 1700);
DISPLAY 0.872340 (-3227 1700);
PAINT GREEN (-3227 1700);
DISPLAY INVISIBLE (-3227 1700);
FORCEADD TAP..1
R 2
(-5650 6000);
FORCEPROP 3 LASTPIN (-5600 6000) SIG_NAME M_L_CPU0_SA_DQS_DP<0>
J 0
(-5590 6010);
DISPLAY 0.659574 (-5590 6010);
PAINT MONO (-5590 6010);
DISPLAY INVISIBLE (-5590 6010);
FORCEPROP 1 LASTPIN (-5600 6000) BN 0
J 2
(-5588 6008);
DISPLAY 0.489362 (-5588 6008);
PAINT GREEN (-5588 6008);
FORCEPROP 2 LAST CDS_LIB mstr_standard
J 2
(-5650 6000);
DISPLAY 0.723404 (-5650 6000);
PAINT MONO (-5650 6000);
DISPLAY INVISIBLE (-5650 6000);
FORCEPROP 1 LAST BODY_TYPE PLUMBING
J 2
(-5650 6050);
DISPLAY 0.872340 (-5650 6050);
PAINT GREEN (-5650 6050);
DISPLAY INVISIBLE (-5650 6050);
FORCEPROP 1 LAST HDL_TAP TRUE
J 2
(-5975 5875);
DISPLAY 0.872340 (-5975 5875);
DISPLAY INVISIBLE (-5975 5875);
FORCEPROP 1 LAST PATH I244
J 2
(-5648 6000);
DISPLAY 0.872340 (-5648 6000);
PAINT GREEN (-5648 6000);
DISPLAY INVISIBLE (-5648 6000);
FORCEADD TAP..1
R 2
(-5650 5900);
FORCEPROP 3 LASTPIN (-5600 5900) SIG_NAME M_L_CPU0_SA_DQS_DP<1>
J 0
(-5590 5910);
DISPLAY 0.659574 (-5590 5910);
PAINT MONO (-5590 5910);
DISPLAY INVISIBLE (-5590 5910);
FORCEPROP 1 LASTPIN (-5600 5900) BN 1
J 2
(-5588 5908);
DISPLAY 0.489362 (-5588 5908);
PAINT GREEN (-5588 5908);
FORCEPROP 2 LAST CDS_LIB mstr_standard
J 2
(-5650 5900);
DISPLAY 0.723404 (-5650 5900);
PAINT MONO (-5650 5900);
DISPLAY INVISIBLE (-5650 5900);
FORCEPROP 1 LAST BODY_TYPE PLUMBING
J 2
(-5650 5950);
DISPLAY 0.872340 (-5650 5950);
PAINT GREEN (-5650 5950);
DISPLAY INVISIBLE (-5650 5950);
FORCEPROP 1 LAST HDL_TAP TRUE
J 2
(-5975 5775);
DISPLAY 0.872340 (-5975 5775);
DISPLAY INVISIBLE (-5975 5775);
FORCEPROP 1 LAST PATH I245
J 2
(-5648 5900);
DISPLAY 0.872340 (-5648 5900);
PAINT GREEN (-5648 5900);
DISPLAY INVISIBLE (-5648 5900);
FORCEADD TAP..1
R 2
(-5650 5800);
FORCEPROP 3 LASTPIN (-5600 5800) SIG_NAME M_L_CPU0_SA_DQS_DP<2>
J 0
(-5590 5810);
DISPLAY 0.659574 (-5590 5810);
PAINT MONO (-5590 5810);
DISPLAY INVISIBLE (-5590 5810);
FORCEPROP 1 LASTPIN (-5600 5800) BN 2
J 2
(-5588 5808);
DISPLAY 0.489362 (-5588 5808);
PAINT GREEN (-5588 5808);
FORCEPROP 2 LAST CDS_LIB mstr_standard
J 2
(-5650 5800);
DISPLAY 0.723404 (-5650 5800);
PAINT MONO (-5650 5800);
DISPLAY INVISIBLE (-5650 5800);
FORCEPROP 1 LAST BODY_TYPE PLUMBING
J 2
(-5650 5850);
DISPLAY 0.872340 (-5650 5850);
PAINT GREEN (-5650 5850);
DISPLAY INVISIBLE (-5650 5850);
FORCEPROP 1 LAST HDL_TAP TRUE
J 2
(-5975 5675);
DISPLAY 0.872340 (-5975 5675);
DISPLAY INVISIBLE (-5975 5675);
FORCEPROP 1 LAST PATH I246
J 2
(-5648 5800);
DISPLAY 0.872340 (-5648 5800);
PAINT GREEN (-5648 5800);
DISPLAY INVISIBLE (-5648 5800);
FORCEADD TAP..1
R 2
(-5650 5700);
FORCEPROP 3 LASTPIN (-5600 5700) SIG_NAME M_L_CPU0_SA_DQS_DP<3>
J 0
(-5590 5710);
DISPLAY 0.659574 (-5590 5710);
PAINT MONO (-5590 5710);
DISPLAY INVISIBLE (-5590 5710);
FORCEPROP 1 LASTPIN (-5600 5700) BN 3
J 2
(-5588 5708);
DISPLAY 0.489362 (-5588 5708);
PAINT GREEN (-5588 5708);
FORCEPROP 2 LAST CDS_LIB mstr_standard
J 2
(-5650 5700);
DISPLAY 0.723404 (-5650 5700);
PAINT MONO (-5650 5700);
DISPLAY INVISIBLE (-5650 5700);
FORCEPROP 1 LAST BODY_TYPE PLUMBING
J 2
(-5650 5750);
DISPLAY 0.872340 (-5650 5750);
PAINT GREEN (-5650 5750);
DISPLAY INVISIBLE (-5650 5750);
FORCEPROP 1 LAST HDL_TAP TRUE
J 2
(-5975 5575);
DISPLAY 0.872340 (-5975 5575);
DISPLAY INVISIBLE (-5975 5575);
FORCEPROP 1 LAST PATH I247
J 2
(-5648 5700);
DISPLAY 0.872340 (-5648 5700);
PAINT GREEN (-5648 5700);
DISPLAY INVISIBLE (-5648 5700);
FORCEADD TAP..1
R 2
(-5650 5600);
FORCEPROP 3 LASTPIN (-5600 5600) SIG_NAME M_L_CPU0_SA_DQS_DP<4>
J 0
(-5590 5610);
DISPLAY 0.659574 (-5590 5610);
PAINT MONO (-5590 5610);
DISPLAY INVISIBLE (-5590 5610);
FORCEPROP 1 LASTPIN (-5600 5600) BN 4
J 2
(-5588 5608);
DISPLAY 0.489362 (-5588 5608);
PAINT GREEN (-5588 5608);
FORCEPROP 2 LAST CDS_LIB mstr_standard
J 2
(-5650 5600);
DISPLAY 0.723404 (-5650 5600);
PAINT MONO (-5650 5600);
DISPLAY INVISIBLE (-5650 5600);
FORCEPROP 1 LAST BODY_TYPE PLUMBING
J 2
(-5650 5650);
DISPLAY 0.872340 (-5650 5650);
PAINT GREEN (-5650 5650);
DISPLAY INVISIBLE (-5650 5650);
FORCEPROP 1 LAST HDL_TAP TRUE
J 2
(-5975 5475);
DISPLAY 0.872340 (-5975 5475);
DISPLAY INVISIBLE (-5975 5475);
FORCEPROP 1 LAST PATH I248
J 2
(-5648 5600);
DISPLAY 0.872340 (-5648 5600);
PAINT GREEN (-5648 5600);
DISPLAY INVISIBLE (-5648 5600);
FORCEADD TAP..1
R 2
(-5650 5400);
FORCEPROP 3 LASTPIN (-5600 5400) SIG_NAME M_L_CPU0_SA_DQS_DP<6>
J 0
(-5590 5410);
DISPLAY 0.659574 (-5590 5410);
PAINT MONO (-5590 5410);
DISPLAY INVISIBLE (-5590 5410);
FORCEPROP 1 LASTPIN (-5600 5400) BN 6
J 2
(-5588 5408);
DISPLAY 0.489362 (-5588 5408);
PAINT GREEN (-5588 5408);
FORCEPROP 2 LAST CDS_LIB mstr_standard
J 2
(-5650 5400);
DISPLAY 0.723404 (-5650 5400);
PAINT MONO (-5650 5400);
DISPLAY INVISIBLE (-5650 5400);
FORCEPROP 1 LAST BODY_TYPE PLUMBING
J 2
(-5650 5450);
DISPLAY 0.872340 (-5650 5450);
PAINT GREEN (-5650 5450);
DISPLAY INVISIBLE (-5650 5450);
FORCEPROP 1 LAST HDL_TAP TRUE
J 2
(-5975 5275);
DISPLAY 0.872340 (-5975 5275);
DISPLAY INVISIBLE (-5975 5275);
FORCEPROP 1 LAST PATH I249
J 2
(-5648 5400);
DISPLAY 0.872340 (-5648 5400);
PAINT GREEN (-5648 5400);
DISPLAY INVISIBLE (-5648 5400);
FORCEADD TAP..1
R 2
(-5650 5500);
FORCEPROP 3 LASTPIN (-5600 5500) SIG_NAME M_L_CPU0_SA_DQS_DP<5>
J 0
(-5590 5510);
DISPLAY 0.659574 (-5590 5510);
PAINT MONO (-5590 5510);
DISPLAY INVISIBLE (-5590 5510);
FORCEPROP 1 LASTPIN (-5600 5500) BN 5
J 2
(-5588 5508);
DISPLAY 0.489362 (-5588 5508);
PAINT GREEN (-5588 5508);
FORCEPROP 2 LAST CDS_LIB mstr_standard
J 2
(-5650 5500);
DISPLAY 0.723404 (-5650 5500);
PAINT MONO (-5650 5500);
DISPLAY INVISIBLE (-5650 5500);
FORCEPROP 1 LAST BODY_TYPE PLUMBING
J 2
(-5650 5550);
DISPLAY 0.872340 (-5650 5550);
PAINT GREEN (-5650 5550);
DISPLAY INVISIBLE (-5650 5550);
FORCEPROP 1 LAST HDL_TAP TRUE
J 2
(-5975 5375);
DISPLAY 0.872340 (-5975 5375);
DISPLAY INVISIBLE (-5975 5375);
FORCEPROP 1 LAST PATH I250
J 2
(-5648 5500);
DISPLAY 0.872340 (-5648 5500);
PAINT GREEN (-5648 5500);
DISPLAY INVISIBLE (-5648 5500);
FORCEADD TAP..1
R 2
(-5650 5300);
FORCEPROP 3 LASTPIN (-5600 5300) SIG_NAME M_L_CPU0_SA_DQS_DP<7>
J 0
(-5590 5310);
DISPLAY 0.659574 (-5590 5310);
PAINT MONO (-5590 5310);
DISPLAY INVISIBLE (-5590 5310);
FORCEPROP 1 LASTPIN (-5600 5300) BN 7
J 2
(-5588 5308);
DISPLAY 0.489362 (-5588 5308);
PAINT GREEN (-5588 5308);
FORCEPROP 2 LAST CDS_LIB mstr_standard
J 2
(-5650 5300);
DISPLAY 0.723404 (-5650 5300);
PAINT MONO (-5650 5300);
DISPLAY INVISIBLE (-5650 5300);
FORCEPROP 1 LAST BODY_TYPE PLUMBING
J 2
(-5650 5350);
DISPLAY 0.872340 (-5650 5350);
PAINT GREEN (-5650 5350);
DISPLAY INVISIBLE (-5650 5350);
FORCEPROP 1 LAST HDL_TAP TRUE
J 2
(-5975 5175);
DISPLAY 0.872340 (-5975 5175);
DISPLAY INVISIBLE (-5975 5175);
FORCEPROP 1 LAST PATH I251
J 2
(-5648 5300);
DISPLAY 0.872340 (-5648 5300);
PAINT GREEN (-5648 5300);
DISPLAY INVISIBLE (-5648 5300);
FORCEADD TAP..1
R 2
(-5650 5200);
FORCEPROP 3 LASTPIN (-5600 5200) SIG_NAME M_L_CPU0_SA_DQS_DP<8>
J 0
(-5590 5210);
DISPLAY 0.659574 (-5590 5210);
PAINT MONO (-5590 5210);
DISPLAY INVISIBLE (-5590 5210);
FORCEPROP 1 LASTPIN (-5600 5200) BN 8
J 2
(-5588 5208);
DISPLAY 0.489362 (-5588 5208);
PAINT GREEN (-5588 5208);
FORCEPROP 2 LAST CDS_LIB mstr_standard
J 2
(-5650 5200);
DISPLAY 0.723404 (-5650 5200);
PAINT MONO (-5650 5200);
DISPLAY INVISIBLE (-5650 5200);
FORCEPROP 1 LAST BODY_TYPE PLUMBING
J 2
(-5650 5250);
DISPLAY 0.872340 (-5650 5250);
PAINT GREEN (-5650 5250);
DISPLAY INVISIBLE (-5650 5250);
FORCEPROP 1 LAST HDL_TAP TRUE
J 2
(-5975 5075);
DISPLAY 0.872340 (-5975 5075);
DISPLAY INVISIBLE (-5975 5075);
FORCEPROP 1 LAST PATH I252
J 2
(-5648 5200);
DISPLAY 0.872340 (-5648 5200);
PAINT GREEN (-5648 5200);
DISPLAY INVISIBLE (-5648 5200);
FORCEADD TAP..1
R 2
(-5850 5950);
FORCEPROP 3 LASTPIN (-5800 5950) SIG_NAME M_L_CPU0_SA_DQS_DN<0>
J 0
(-5790 5960);
DISPLAY 0.659574 (-5790 5960);
PAINT MONO (-5790 5960);
DISPLAY INVISIBLE (-5790 5960);
FORCEPROP 1 LASTPIN (-5800 5950) BN 0
J 2
(-5788 5958);
DISPLAY 0.489362 (-5788 5958);
PAINT GREEN (-5788 5958);
FORCEPROP 2 LAST CDS_LIB mstr_standard
J 2
(-5850 5950);
DISPLAY 0.723404 (-5850 5950);
PAINT MONO (-5850 5950);
DISPLAY INVISIBLE (-5850 5950);
FORCEPROP 1 LAST BODY_TYPE PLUMBING
J 2
(-5850 6000);
DISPLAY 0.872340 (-5850 6000);
PAINT GREEN (-5850 6000);
DISPLAY INVISIBLE (-5850 6000);
FORCEPROP 1 LAST HDL_TAP TRUE
J 2
(-6175 5825);
DISPLAY 0.872340 (-6175 5825);
DISPLAY INVISIBLE (-6175 5825);
FORCEPROP 1 LAST PATH I253
J 2
(-5848 5950);
DISPLAY 0.872340 (-5848 5950);
PAINT GREEN (-5848 5950);
DISPLAY INVISIBLE (-5848 5950);
FORCEADD TAP..1
R 2
(-5850 5850);
FORCEPROP 3 LASTPIN (-5800 5850) SIG_NAME M_L_CPU0_SA_DQS_DN<1>
J 0
(-5790 5860);
DISPLAY 0.659574 (-5790 5860);
PAINT MONO (-5790 5860);
DISPLAY INVISIBLE (-5790 5860);
FORCEPROP 1 LASTPIN (-5800 5850) BN 1
J 2
(-5788 5858);
DISPLAY 0.489362 (-5788 5858);
PAINT GREEN (-5788 5858);
FORCEPROP 2 LAST CDS_LIB mstr_standard
J 2
(-5850 5850);
DISPLAY 0.723404 (-5850 5850);
PAINT MONO (-5850 5850);
DISPLAY INVISIBLE (-5850 5850);
FORCEPROP 1 LAST BODY_TYPE PLUMBING
J 2
(-5850 5900);
DISPLAY 0.872340 (-5850 5900);
PAINT GREEN (-5850 5900);
DISPLAY INVISIBLE (-5850 5900);
FORCEPROP 1 LAST HDL_TAP TRUE
J 2
(-6175 5725);
DISPLAY 0.872340 (-6175 5725);
DISPLAY INVISIBLE (-6175 5725);
FORCEPROP 1 LAST PATH I254
J 2
(-5848 5850);
DISPLAY 0.872340 (-5848 5850);
PAINT GREEN (-5848 5850);
DISPLAY INVISIBLE (-5848 5850);
FORCEADD TAP..1
R 2
(-5850 5750);
FORCEPROP 3 LASTPIN (-5800 5750) SIG_NAME M_L_CPU0_SA_DQS_DN<2>
J 0
(-5790 5760);
DISPLAY 0.659574 (-5790 5760);
PAINT MONO (-5790 5760);
DISPLAY INVISIBLE (-5790 5760);
FORCEPROP 1 LASTPIN (-5800 5750) BN 2
J 2
(-5788 5758);
DISPLAY 0.489362 (-5788 5758);
PAINT GREEN (-5788 5758);
FORCEPROP 2 LAST CDS_LIB mstr_standard
J 2
(-5850 5750);
DISPLAY 0.723404 (-5850 5750);
PAINT MONO (-5850 5750);
DISPLAY INVISIBLE (-5850 5750);
FORCEPROP 1 LAST BODY_TYPE PLUMBING
J 2
(-5850 5800);
DISPLAY 0.872340 (-5850 5800);
PAINT GREEN (-5850 5800);
DISPLAY INVISIBLE (-5850 5800);
FORCEPROP 1 LAST HDL_TAP TRUE
J 2
(-6175 5625);
DISPLAY 0.872340 (-6175 5625);
DISPLAY INVISIBLE (-6175 5625);
FORCEPROP 1 LAST PATH I255
J 2
(-5848 5750);
DISPLAY 0.872340 (-5848 5750);
PAINT GREEN (-5848 5750);
DISPLAY INVISIBLE (-5848 5750);
FORCEADD TAP..1
R 2
(-5850 5650);
FORCEPROP 3 LASTPIN (-5800 5650) SIG_NAME M_L_CPU0_SA_DQS_DN<3>
J 0
(-5790 5660);
DISPLAY 0.659574 (-5790 5660);
PAINT MONO (-5790 5660);
DISPLAY INVISIBLE (-5790 5660);
FORCEPROP 1 LASTPIN (-5800 5650) BN 3
J 2
(-5788 5658);
DISPLAY 0.489362 (-5788 5658);
PAINT GREEN (-5788 5658);
FORCEPROP 2 LAST CDS_LIB mstr_standard
J 2
(-5850 5650);
DISPLAY 0.723404 (-5850 5650);
PAINT MONO (-5850 5650);
DISPLAY INVISIBLE (-5850 5650);
FORCEPROP 1 LAST BODY_TYPE PLUMBING
J 2
(-5850 5700);
DISPLAY 0.872340 (-5850 5700);
PAINT GREEN (-5850 5700);
DISPLAY INVISIBLE (-5850 5700);
FORCEPROP 1 LAST HDL_TAP TRUE
J 2
(-6175 5525);
DISPLAY 0.872340 (-6175 5525);
DISPLAY INVISIBLE (-6175 5525);
FORCEPROP 1 LAST PATH I256
J 2
(-5848 5650);
DISPLAY 0.872340 (-5848 5650);
PAINT GREEN (-5848 5650);
DISPLAY INVISIBLE (-5848 5650);
FORCEADD TAP..1
R 2
(-5850 5450);
FORCEPROP 3 LASTPIN (-5800 5450) SIG_NAME M_L_CPU0_SA_DQS_DN<5>
J 0
(-5790 5460);
DISPLAY 0.659574 (-5790 5460);
PAINT MONO (-5790 5460);
DISPLAY INVISIBLE (-5790 5460);
FORCEPROP 1 LASTPIN (-5800 5450) BN 5
J 2
(-5788 5458);
DISPLAY 0.489362 (-5788 5458);
PAINT GREEN (-5788 5458);
FORCEPROP 2 LAST CDS_LIB mstr_standard
J 2
(-5850 5450);
DISPLAY 0.723404 (-5850 5450);
PAINT MONO (-5850 5450);
DISPLAY INVISIBLE (-5850 5450);
FORCEPROP 1 LAST BODY_TYPE PLUMBING
J 2
(-5850 5500);
DISPLAY 0.872340 (-5850 5500);
PAINT GREEN (-5850 5500);
DISPLAY INVISIBLE (-5850 5500);
FORCEPROP 1 LAST HDL_TAP TRUE
J 2
(-6175 5325);
DISPLAY 0.872340 (-6175 5325);
DISPLAY INVISIBLE (-6175 5325);
FORCEPROP 1 LAST PATH I257
J 2
(-5848 5450);
DISPLAY 0.872340 (-5848 5450);
PAINT GREEN (-5848 5450);
DISPLAY INVISIBLE (-5848 5450);
FORCEADD TAP..1
R 2
(-5850 5550);
FORCEPROP 3 LASTPIN (-5800 5550) SIG_NAME M_L_CPU0_SA_DQS_DN<4>
J 0
(-5790 5560);
DISPLAY 0.659574 (-5790 5560);
PAINT MONO (-5790 5560);
DISPLAY INVISIBLE (-5790 5560);
FORCEPROP 1 LASTPIN (-5800 5550) BN 4
J 2
(-5788 5558);
DISPLAY 0.489362 (-5788 5558);
PAINT GREEN (-5788 5558);
FORCEPROP 2 LAST CDS_LIB mstr_standard
J 2
(-5850 5550);
DISPLAY 0.723404 (-5850 5550);
PAINT MONO (-5850 5550);
DISPLAY INVISIBLE (-5850 5550);
FORCEPROP 1 LAST BODY_TYPE PLUMBING
J 2
(-5850 5600);
DISPLAY 0.872340 (-5850 5600);
PAINT GREEN (-5850 5600);
DISPLAY INVISIBLE (-5850 5600);
FORCEPROP 1 LAST HDL_TAP TRUE
J 2
(-6175 5425);
DISPLAY 0.872340 (-6175 5425);
DISPLAY INVISIBLE (-6175 5425);
FORCEPROP 1 LAST PATH I258
J 2
(-5848 5550);
DISPLAY 0.872340 (-5848 5550);
PAINT GREEN (-5848 5550);
DISPLAY INVISIBLE (-5848 5550);
FORCEADD TAP..1
R 2
(-5850 5350);
FORCEPROP 3 LASTPIN (-5800 5350) SIG_NAME M_L_CPU0_SA_DQS_DN<6>
J 0
(-5790 5360);
DISPLAY 0.659574 (-5790 5360);
PAINT MONO (-5790 5360);
DISPLAY INVISIBLE (-5790 5360);
FORCEPROP 1 LASTPIN (-5800 5350) BN 6
J 2
(-5788 5358);
DISPLAY 0.489362 (-5788 5358);
PAINT GREEN (-5788 5358);
FORCEPROP 2 LAST CDS_LIB mstr_standard
J 2
(-5850 5350);
DISPLAY 0.723404 (-5850 5350);
PAINT MONO (-5850 5350);
DISPLAY INVISIBLE (-5850 5350);
FORCEPROP 1 LAST BODY_TYPE PLUMBING
J 2
(-5850 5400);
DISPLAY 0.872340 (-5850 5400);
PAINT GREEN (-5850 5400);
DISPLAY INVISIBLE (-5850 5400);
FORCEPROP 1 LAST HDL_TAP TRUE
J 2
(-6175 5225);
DISPLAY 0.872340 (-6175 5225);
DISPLAY INVISIBLE (-6175 5225);
FORCEPROP 1 LAST PATH I259
J 2
(-5848 5350);
DISPLAY 0.872340 (-5848 5350);
PAINT GREEN (-5848 5350);
DISPLAY INVISIBLE (-5848 5350);
FORCEADD TAP..1
R 2
(-5850 5250);
FORCEPROP 3 LASTPIN (-5800 5250) SIG_NAME M_L_CPU0_SA_DQS_DN<7>
J 0
(-5790 5260);
DISPLAY 0.659574 (-5790 5260);
PAINT MONO (-5790 5260);
DISPLAY INVISIBLE (-5790 5260);
FORCEPROP 1 LASTPIN (-5800 5250) BN 7
J 2
(-5788 5258);
DISPLAY 0.489362 (-5788 5258);
PAINT GREEN (-5788 5258);
FORCEPROP 2 LAST CDS_LIB mstr_standard
J 2
(-5850 5250);
DISPLAY 0.723404 (-5850 5250);
PAINT MONO (-5850 5250);
DISPLAY INVISIBLE (-5850 5250);
FORCEPROP 1 LAST BODY_TYPE PLUMBING
J 2
(-5850 5300);
DISPLAY 0.872340 (-5850 5300);
PAINT GREEN (-5850 5300);
DISPLAY INVISIBLE (-5850 5300);
FORCEPROP 1 LAST HDL_TAP TRUE
J 2
(-6175 5125);
DISPLAY 0.872340 (-6175 5125);
DISPLAY INVISIBLE (-6175 5125);
FORCEPROP 1 LAST PATH I260
J 2
(-5848 5250);
DISPLAY 0.872340 (-5848 5250);
PAINT GREEN (-5848 5250);
DISPLAY INVISIBLE (-5848 5250);
FORCEADD TAP..1
R 2
(-5850 5150);
FORCEPROP 3 LASTPIN (-5800 5150) SIG_NAME M_L_CPU0_SA_DQS_DN<8>
J 0
(-5790 5160);
DISPLAY 0.659574 (-5790 5160);
PAINT MONO (-5790 5160);
DISPLAY INVISIBLE (-5790 5160);
FORCEPROP 1 LASTPIN (-5800 5150) BN 8
J 2
(-5788 5158);
DISPLAY 0.489362 (-5788 5158);
PAINT GREEN (-5788 5158);
FORCEPROP 2 LAST CDS_LIB mstr_standard
J 2
(-5850 5150);
DISPLAY 0.723404 (-5850 5150);
PAINT MONO (-5850 5150);
DISPLAY INVISIBLE (-5850 5150);
FORCEPROP 1 LAST BODY_TYPE PLUMBING
J 2
(-5850 5200);
DISPLAY 0.872340 (-5850 5200);
PAINT GREEN (-5850 5200);
DISPLAY INVISIBLE (-5850 5200);
FORCEPROP 1 LAST HDL_TAP TRUE
J 2
(-6175 5025);
DISPLAY 0.872340 (-6175 5025);
DISPLAY INVISIBLE (-6175 5025);
FORCEPROP 1 LAST PATH I261
J 2
(-5848 5150);
DISPLAY 0.872340 (-5848 5150);
PAINT GREEN (-5848 5150);
DISPLAY INVISIBLE (-5848 5150);
FORCEADD TAP..1
R 2
(-5650 5100);
FORCEPROP 3 LASTPIN (-5600 5100) SIG_NAME M_L_CPU0_SA_DQS_DP<9>
J 0
(-5590 5110);
DISPLAY 0.659574 (-5590 5110);
PAINT MONO (-5590 5110);
DISPLAY INVISIBLE (-5590 5110);
FORCEPROP 1 LASTPIN (-5600 5100) BN 9
J 2
(-5588 5108);
DISPLAY 0.489362 (-5588 5108);
PAINT GREEN (-5588 5108);
FORCEPROP 2 LAST CDS_LIB mstr_standard
J 2
(-5650 5100);
DISPLAY 0.723404 (-5650 5100);
PAINT MONO (-5650 5100);
DISPLAY INVISIBLE (-5650 5100);
FORCEPROP 1 LAST BODY_TYPE PLUMBING
J 2
(-5650 5150);
DISPLAY 0.872340 (-5650 5150);
PAINT GREEN (-5650 5150);
DISPLAY INVISIBLE (-5650 5150);
FORCEPROP 1 LAST HDL_TAP TRUE
J 2
(-5975 4975);
DISPLAY 0.872340 (-5975 4975);
DISPLAY INVISIBLE (-5975 4975);
FORCEPROP 1 LAST PATH I262
J 2
(-5648 5100);
DISPLAY 0.872340 (-5648 5100);
PAINT GREEN (-5648 5100);
DISPLAY INVISIBLE (-5648 5100);
FORCEADD TAP..1
R 2
(-5650 4950);
FORCEPROP 3 LASTPIN (-5600 4950) SIG_NAME M_L_CPU0_SB_DQS_DP<0>
J 0
(-5590 4960);
DISPLAY 0.659574 (-5590 4960);
PAINT MONO (-5590 4960);
DISPLAY INVISIBLE (-5590 4960);
FORCEPROP 1 LASTPIN (-5600 4950) BN 0
J 2
(-5588 4958);
DISPLAY 0.489362 (-5588 4958);
PAINT GREEN (-5588 4958);
FORCEPROP 2 LAST CDS_LIB mstr_standard
J 2
(-5650 4950);
DISPLAY 0.723404 (-5650 4950);
PAINT MONO (-5650 4950);
DISPLAY INVISIBLE (-5650 4950);
FORCEPROP 1 LAST BODY_TYPE PLUMBING
J 2
(-5650 5000);
DISPLAY 0.872340 (-5650 5000);
PAINT GREEN (-5650 5000);
DISPLAY INVISIBLE (-5650 5000);
FORCEPROP 1 LAST HDL_TAP TRUE
J 2
(-5975 4825);
DISPLAY 0.872340 (-5975 4825);
DISPLAY INVISIBLE (-5975 4825);
FORCEPROP 1 LAST PATH I263
J 2
(-5648 4950);
DISPLAY 0.872340 (-5648 4950);
PAINT GREEN (-5648 4950);
DISPLAY INVISIBLE (-5648 4950);
FORCEADD TAP..1
R 2
(-5650 4850);
FORCEPROP 3 LASTPIN (-5600 4850) SIG_NAME M_L_CPU0_SB_DQS_DP<1>
J 0
(-5590 4860);
DISPLAY 0.659574 (-5590 4860);
PAINT MONO (-5590 4860);
DISPLAY INVISIBLE (-5590 4860);
FORCEPROP 1 LASTPIN (-5600 4850) BN 1
J 2
(-5588 4858);
DISPLAY 0.489362 (-5588 4858);
PAINT GREEN (-5588 4858);
FORCEPROP 2 LAST CDS_LIB mstr_standard
J 2
(-5650 4850);
DISPLAY 0.723404 (-5650 4850);
PAINT MONO (-5650 4850);
DISPLAY INVISIBLE (-5650 4850);
FORCEPROP 1 LAST BODY_TYPE PLUMBING
J 2
(-5650 4900);
DISPLAY 0.872340 (-5650 4900);
PAINT GREEN (-5650 4900);
DISPLAY INVISIBLE (-5650 4900);
FORCEPROP 1 LAST HDL_TAP TRUE
J 2
(-5975 4725);
DISPLAY 0.872340 (-5975 4725);
DISPLAY INVISIBLE (-5975 4725);
FORCEPROP 1 LAST PATH I264
J 2
(-5648 4850);
DISPLAY 0.872340 (-5648 4850);
PAINT GREEN (-5648 4850);
DISPLAY INVISIBLE (-5648 4850);
FORCEADD TAP..1
R 2
(-5650 4750);
FORCEPROP 3 LASTPIN (-5600 4750) SIG_NAME M_L_CPU0_SB_DQS_DP<2>
J 0
(-5590 4760);
DISPLAY 0.659574 (-5590 4760);
PAINT MONO (-5590 4760);
DISPLAY INVISIBLE (-5590 4760);
FORCEPROP 1 LASTPIN (-5600 4750) BN 2
J 2
(-5588 4758);
DISPLAY 0.489362 (-5588 4758);
PAINT GREEN (-5588 4758);
FORCEPROP 2 LAST CDS_LIB mstr_standard
J 2
(-5650 4750);
DISPLAY 0.723404 (-5650 4750);
PAINT MONO (-5650 4750);
DISPLAY INVISIBLE (-5650 4750);
FORCEPROP 1 LAST BODY_TYPE PLUMBING
J 2
(-5650 4800);
DISPLAY 0.872340 (-5650 4800);
PAINT GREEN (-5650 4800);
DISPLAY INVISIBLE (-5650 4800);
FORCEPROP 1 LAST HDL_TAP TRUE
J 2
(-5975 4625);
DISPLAY 0.872340 (-5975 4625);
DISPLAY INVISIBLE (-5975 4625);
FORCEPROP 1 LAST PATH I265
J 2
(-5648 4750);
DISPLAY 0.872340 (-5648 4750);
PAINT GREEN (-5648 4750);
DISPLAY INVISIBLE (-5648 4750);
FORCEADD TAP..1
R 2
(-5650 4650);
FORCEPROP 3 LASTPIN (-5600 4650) SIG_NAME M_L_CPU0_SB_DQS_DP<3>
J 0
(-5590 4660);
DISPLAY 0.659574 (-5590 4660);
PAINT MONO (-5590 4660);
DISPLAY INVISIBLE (-5590 4660);
FORCEPROP 1 LASTPIN (-5600 4650) BN 3
J 2
(-5588 4658);
DISPLAY 0.489362 (-5588 4658);
PAINT GREEN (-5588 4658);
FORCEPROP 2 LAST CDS_LIB mstr_standard
J 2
(-5650 4650);
DISPLAY 0.723404 (-5650 4650);
PAINT MONO (-5650 4650);
DISPLAY INVISIBLE (-5650 4650);
FORCEPROP 1 LAST BODY_TYPE PLUMBING
J 2
(-5650 4700);
DISPLAY 0.872340 (-5650 4700);
PAINT GREEN (-5650 4700);
DISPLAY INVISIBLE (-5650 4700);
FORCEPROP 1 LAST HDL_TAP TRUE
J 2
(-5975 4525);
DISPLAY 0.872340 (-5975 4525);
DISPLAY INVISIBLE (-5975 4525);
FORCEPROP 1 LAST PATH I266
J 2
(-5648 4650);
DISPLAY 0.872340 (-5648 4650);
PAINT GREEN (-5648 4650);
DISPLAY INVISIBLE (-5648 4650);
FORCEADD TAP..1
R 2
(-5650 4550);
FORCEPROP 3 LASTPIN (-5600 4550) SIG_NAME M_L_CPU0_SB_DQS_DP<4>
J 0
(-5590 4560);
DISPLAY 0.659574 (-5590 4560);
PAINT MONO (-5590 4560);
DISPLAY INVISIBLE (-5590 4560);
FORCEPROP 1 LASTPIN (-5600 4550) BN 4
J 2
(-5588 4558);
DISPLAY 0.489362 (-5588 4558);
PAINT GREEN (-5588 4558);
FORCEPROP 2 LAST CDS_LIB mstr_standard
J 2
(-5650 4550);
DISPLAY 0.723404 (-5650 4550);
PAINT MONO (-5650 4550);
DISPLAY INVISIBLE (-5650 4550);
FORCEPROP 1 LAST BODY_TYPE PLUMBING
J 2
(-5650 4600);
DISPLAY 0.872340 (-5650 4600);
PAINT GREEN (-5650 4600);
DISPLAY INVISIBLE (-5650 4600);
FORCEPROP 1 LAST HDL_TAP TRUE
J 2
(-5975 4425);
DISPLAY 0.872340 (-5975 4425);
DISPLAY INVISIBLE (-5975 4425);
FORCEPROP 1 LAST PATH I267
J 2
(-5648 4550);
DISPLAY 0.872340 (-5648 4550);
PAINT GREEN (-5648 4550);
DISPLAY INVISIBLE (-5648 4550);
FORCEADD TAP..1
R 2
(-5650 4450);
FORCEPROP 3 LASTPIN (-5600 4450) SIG_NAME M_L_CPU0_SB_DQS_DP<5>
J 0
(-5590 4460);
DISPLAY 0.659574 (-5590 4460);
PAINT MONO (-5590 4460);
DISPLAY INVISIBLE (-5590 4460);
FORCEPROP 1 LASTPIN (-5600 4450) BN 5
J 2
(-5588 4458);
DISPLAY 0.489362 (-5588 4458);
PAINT GREEN (-5588 4458);
FORCEPROP 2 LAST CDS_LIB mstr_standard
J 2
(-5650 4450);
DISPLAY 0.723404 (-5650 4450);
PAINT MONO (-5650 4450);
DISPLAY INVISIBLE (-5650 4450);
FORCEPROP 1 LAST BODY_TYPE PLUMBING
J 2
(-5650 4500);
DISPLAY 0.872340 (-5650 4500);
PAINT GREEN (-5650 4500);
DISPLAY INVISIBLE (-5650 4500);
FORCEPROP 1 LAST HDL_TAP TRUE
J 2
(-5975 4325);
DISPLAY 0.872340 (-5975 4325);
DISPLAY INVISIBLE (-5975 4325);
FORCEPROP 1 LAST PATH I268
J 2
(-5648 4450);
DISPLAY 0.872340 (-5648 4450);
PAINT GREEN (-5648 4450);
DISPLAY INVISIBLE (-5648 4450);
FORCEADD TAP..1
R 2
(-5650 4350);
FORCEPROP 3 LASTPIN (-5600 4350) SIG_NAME M_L_CPU0_SB_DQS_DP<6>
J 0
(-5590 4360);
DISPLAY 0.659574 (-5590 4360);
PAINT MONO (-5590 4360);
DISPLAY INVISIBLE (-5590 4360);
FORCEPROP 1 LASTPIN (-5600 4350) BN 6
J 2
(-5588 4358);
DISPLAY 0.489362 (-5588 4358);
PAINT GREEN (-5588 4358);
FORCEPROP 2 LAST CDS_LIB mstr_standard
J 2
(-5650 4350);
DISPLAY 0.723404 (-5650 4350);
PAINT MONO (-5650 4350);
DISPLAY INVISIBLE (-5650 4350);
FORCEPROP 1 LAST BODY_TYPE PLUMBING
J 2
(-5650 4400);
DISPLAY 0.872340 (-5650 4400);
PAINT GREEN (-5650 4400);
DISPLAY INVISIBLE (-5650 4400);
FORCEPROP 1 LAST HDL_TAP TRUE
J 2
(-5975 4225);
DISPLAY 0.872340 (-5975 4225);
DISPLAY INVISIBLE (-5975 4225);
FORCEPROP 1 LAST PATH I269
J 2
(-5648 4350);
DISPLAY 0.872340 (-5648 4350);
PAINT GREEN (-5648 4350);
DISPLAY INVISIBLE (-5648 4350);
FORCEADD TAP..1
R 2
(-5650 4250);
FORCEPROP 3 LASTPIN (-5600 4250) SIG_NAME M_L_CPU0_SB_DQS_DP<7>
J 0
(-5590 4260);
DISPLAY 0.659574 (-5590 4260);
PAINT MONO (-5590 4260);
DISPLAY INVISIBLE (-5590 4260);
FORCEPROP 1 LASTPIN (-5600 4250) BN 7
J 2
(-5588 4258);
DISPLAY 0.489362 (-5588 4258);
PAINT GREEN (-5588 4258);
FORCEPROP 2 LAST CDS_LIB mstr_standard
J 2
(-5650 4250);
DISPLAY 0.723404 (-5650 4250);
PAINT MONO (-5650 4250);
DISPLAY INVISIBLE (-5650 4250);
FORCEPROP 1 LAST BODY_TYPE PLUMBING
J 2
(-5650 4300);
DISPLAY 0.872340 (-5650 4300);
PAINT GREEN (-5650 4300);
DISPLAY INVISIBLE (-5650 4300);
FORCEPROP 1 LAST HDL_TAP TRUE
J 2
(-5975 4125);
DISPLAY 0.872340 (-5975 4125);
DISPLAY INVISIBLE (-5975 4125);
FORCEPROP 1 LAST PATH I270
J 2
(-5648 4250);
DISPLAY 0.872340 (-5648 4250);
PAINT GREEN (-5648 4250);
DISPLAY INVISIBLE (-5648 4250);
FORCEADD TAP..1
R 2
(-5650 4150);
FORCEPROP 3 LASTPIN (-5600 4150) SIG_NAME M_L_CPU0_SB_DQS_DP<8>
J 0
(-5590 4160);
DISPLAY 0.659574 (-5590 4160);
PAINT MONO (-5590 4160);
DISPLAY INVISIBLE (-5590 4160);
FORCEPROP 1 LASTPIN (-5600 4150) BN 8
J 2
(-5588 4158);
DISPLAY 0.489362 (-5588 4158);
PAINT GREEN (-5588 4158);
FORCEPROP 2 LAST CDS_LIB mstr_standard
J 2
(-5650 4150);
DISPLAY 0.723404 (-5650 4150);
PAINT MONO (-5650 4150);
DISPLAY INVISIBLE (-5650 4150);
FORCEPROP 1 LAST BODY_TYPE PLUMBING
J 2
(-5650 4200);
DISPLAY 0.872340 (-5650 4200);
PAINT GREEN (-5650 4200);
DISPLAY INVISIBLE (-5650 4200);
FORCEPROP 1 LAST HDL_TAP TRUE
J 2
(-5975 4025);
DISPLAY 0.872340 (-5975 4025);
DISPLAY INVISIBLE (-5975 4025);
FORCEPROP 1 LAST PATH I271
J 2
(-5648 4150);
DISPLAY 0.872340 (-5648 4150);
PAINT GREEN (-5648 4150);
DISPLAY INVISIBLE (-5648 4150);
FORCEADD TAP..1
R 2
(-5850 4900);
FORCEPROP 3 LASTPIN (-5800 4900) SIG_NAME M_L_CPU0_SB_DQS_DN<0>
J 0
(-5790 4910);
DISPLAY 0.659574 (-5790 4910);
PAINT MONO (-5790 4910);
DISPLAY INVISIBLE (-5790 4910);
FORCEPROP 1 LASTPIN (-5800 4900) BN 0
J 2
(-5788 4908);
DISPLAY 0.489362 (-5788 4908);
PAINT GREEN (-5788 4908);
FORCEPROP 2 LAST CDS_LIB mstr_standard
J 2
(-5850 4900);
DISPLAY 0.723404 (-5850 4900);
PAINT MONO (-5850 4900);
DISPLAY INVISIBLE (-5850 4900);
FORCEPROP 1 LAST BODY_TYPE PLUMBING
J 2
(-5850 4950);
DISPLAY 0.872340 (-5850 4950);
PAINT GREEN (-5850 4950);
DISPLAY INVISIBLE (-5850 4950);
FORCEPROP 1 LAST HDL_TAP TRUE
J 2
(-6175 4775);
DISPLAY 0.872340 (-6175 4775);
DISPLAY INVISIBLE (-6175 4775);
FORCEPROP 1 LAST PATH I272
J 2
(-5848 4900);
DISPLAY 0.872340 (-5848 4900);
PAINT GREEN (-5848 4900);
DISPLAY INVISIBLE (-5848 4900);
FORCEADD TAP..1
R 2
(-5850 5050);
FORCEPROP 3 LASTPIN (-5800 5050) SIG_NAME M_L_CPU0_SA_DQS_DN<9>
J 0
(-5790 5060);
DISPLAY 0.659574 (-5790 5060);
PAINT MONO (-5790 5060);
DISPLAY INVISIBLE (-5790 5060);
FORCEPROP 1 LASTPIN (-5800 5050) BN 9
J 2
(-5788 5058);
DISPLAY 0.489362 (-5788 5058);
PAINT GREEN (-5788 5058);
FORCEPROP 2 LAST CDS_LIB mstr_standard
J 2
(-5850 5050);
DISPLAY 0.723404 (-5850 5050);
PAINT MONO (-5850 5050);
DISPLAY INVISIBLE (-5850 5050);
FORCEPROP 1 LAST BODY_TYPE PLUMBING
J 2
(-5850 5100);
DISPLAY 0.872340 (-5850 5100);
PAINT GREEN (-5850 5100);
DISPLAY INVISIBLE (-5850 5100);
FORCEPROP 1 LAST HDL_TAP TRUE
J 2
(-6175 4925);
DISPLAY 0.872340 (-6175 4925);
DISPLAY INVISIBLE (-6175 4925);
FORCEPROP 1 LAST PATH I273
J 2
(-5848 5050);
DISPLAY 0.872340 (-5848 5050);
PAINT GREEN (-5848 5050);
DISPLAY INVISIBLE (-5848 5050);
FORCEADD TAP..1
R 2
(-5850 4800);
FORCEPROP 3 LASTPIN (-5800 4800) SIG_NAME M_L_CPU0_SB_DQS_DN<1>
J 0
(-5790 4810);
DISPLAY 0.659574 (-5790 4810);
PAINT MONO (-5790 4810);
DISPLAY INVISIBLE (-5790 4810);
FORCEPROP 1 LASTPIN (-5800 4800) BN 1
J 2
(-5788 4808);
DISPLAY 0.489362 (-5788 4808);
PAINT GREEN (-5788 4808);
FORCEPROP 2 LAST CDS_LIB mstr_standard
J 2
(-5850 4800);
DISPLAY 0.723404 (-5850 4800);
PAINT MONO (-5850 4800);
DISPLAY INVISIBLE (-5850 4800);
FORCEPROP 1 LAST BODY_TYPE PLUMBING
J 2
(-5850 4850);
DISPLAY 0.872340 (-5850 4850);
PAINT GREEN (-5850 4850);
DISPLAY INVISIBLE (-5850 4850);
FORCEPROP 1 LAST HDL_TAP TRUE
J 2
(-6175 4675);
DISPLAY 0.872340 (-6175 4675);
DISPLAY INVISIBLE (-6175 4675);
FORCEPROP 1 LAST PATH I274
J 2
(-5848 4800);
DISPLAY 0.872340 (-5848 4800);
PAINT GREEN (-5848 4800);
DISPLAY INVISIBLE (-5848 4800);
FORCEADD TAP..1
R 2
(-5850 4700);
FORCEPROP 3 LASTPIN (-5800 4700) SIG_NAME M_L_CPU0_SB_DQS_DN<2>
J 0
(-5790 4710);
DISPLAY 0.659574 (-5790 4710);
PAINT MONO (-5790 4710);
DISPLAY INVISIBLE (-5790 4710);
FORCEPROP 1 LASTPIN (-5800 4700) BN 2
J 2
(-5788 4708);
DISPLAY 0.489362 (-5788 4708);
PAINT GREEN (-5788 4708);
FORCEPROP 2 LAST CDS_LIB mstr_standard
J 2
(-5850 4700);
DISPLAY 0.723404 (-5850 4700);
PAINT MONO (-5850 4700);
DISPLAY INVISIBLE (-5850 4700);
FORCEPROP 1 LAST BODY_TYPE PLUMBING
J 2
(-5850 4750);
DISPLAY 0.872340 (-5850 4750);
PAINT GREEN (-5850 4750);
DISPLAY INVISIBLE (-5850 4750);
FORCEPROP 1 LAST HDL_TAP TRUE
J 2
(-6175 4575);
DISPLAY 0.872340 (-6175 4575);
DISPLAY INVISIBLE (-6175 4575);
FORCEPROP 1 LAST PATH I275
J 2
(-5848 4700);
DISPLAY 0.872340 (-5848 4700);
PAINT GREEN (-5848 4700);
DISPLAY INVISIBLE (-5848 4700);
FORCEADD TAP..1
R 2
(-5850 4600);
FORCEPROP 3 LASTPIN (-5800 4600) SIG_NAME M_L_CPU0_SB_DQS_DN<3>
J 0
(-5790 4610);
DISPLAY 0.659574 (-5790 4610);
PAINT MONO (-5790 4610);
DISPLAY INVISIBLE (-5790 4610);
FORCEPROP 1 LASTPIN (-5800 4600) BN 3
J 2
(-5788 4608);
DISPLAY 0.489362 (-5788 4608);
PAINT GREEN (-5788 4608);
FORCEPROP 2 LAST CDS_LIB mstr_standard
J 2
(-5850 4600);
DISPLAY 0.723404 (-5850 4600);
PAINT MONO (-5850 4600);
DISPLAY INVISIBLE (-5850 4600);
FORCEPROP 1 LAST BODY_TYPE PLUMBING
J 2
(-5850 4650);
DISPLAY 0.872340 (-5850 4650);
PAINT GREEN (-5850 4650);
DISPLAY INVISIBLE (-5850 4650);
FORCEPROP 1 LAST HDL_TAP TRUE
J 2
(-6175 4475);
DISPLAY 0.872340 (-6175 4475);
DISPLAY INVISIBLE (-6175 4475);
FORCEPROP 1 LAST PATH I276
J 2
(-5848 4600);
DISPLAY 0.872340 (-5848 4600);
PAINT GREEN (-5848 4600);
DISPLAY INVISIBLE (-5848 4600);
FORCEADD TAP..1
R 2
(-5850 4500);
FORCEPROP 3 LASTPIN (-5800 4500) SIG_NAME M_L_CPU0_SB_DQS_DN<4>
J 0
(-5790 4510);
DISPLAY 0.659574 (-5790 4510);
PAINT MONO (-5790 4510);
DISPLAY INVISIBLE (-5790 4510);
FORCEPROP 1 LASTPIN (-5800 4500) BN 4
J 2
(-5788 4508);
DISPLAY 0.489362 (-5788 4508);
PAINT GREEN (-5788 4508);
FORCEPROP 2 LAST CDS_LIB mstr_standard
J 2
(-5850 4500);
DISPLAY 0.723404 (-5850 4500);
PAINT MONO (-5850 4500);
DISPLAY INVISIBLE (-5850 4500);
FORCEPROP 1 LAST BODY_TYPE PLUMBING
J 2
(-5850 4550);
DISPLAY 0.872340 (-5850 4550);
PAINT GREEN (-5850 4550);
DISPLAY INVISIBLE (-5850 4550);
FORCEPROP 1 LAST HDL_TAP TRUE
J 2
(-6175 4375);
DISPLAY 0.872340 (-6175 4375);
DISPLAY INVISIBLE (-6175 4375);
FORCEPROP 1 LAST PATH I277
J 2
(-5848 4500);
DISPLAY 0.872340 (-5848 4500);
PAINT GREEN (-5848 4500);
DISPLAY INVISIBLE (-5848 4500);
FORCEADD TAP..1
R 2
(-5850 4400);
FORCEPROP 3 LASTPIN (-5800 4400) SIG_NAME M_L_CPU0_SB_DQS_DN<5>
J 0
(-5790 4410);
DISPLAY 0.659574 (-5790 4410);
PAINT MONO (-5790 4410);
DISPLAY INVISIBLE (-5790 4410);
FORCEPROP 1 LASTPIN (-5800 4400) BN 5
J 2
(-5788 4408);
DISPLAY 0.489362 (-5788 4408);
PAINT GREEN (-5788 4408);
FORCEPROP 2 LAST CDS_LIB mstr_standard
J 2
(-5850 4400);
DISPLAY 0.723404 (-5850 4400);
PAINT MONO (-5850 4400);
DISPLAY INVISIBLE (-5850 4400);
FORCEPROP 1 LAST BODY_TYPE PLUMBING
J 2
(-5850 4450);
DISPLAY 0.872340 (-5850 4450);
PAINT GREEN (-5850 4450);
DISPLAY INVISIBLE (-5850 4450);
FORCEPROP 1 LAST HDL_TAP TRUE
J 2
(-6175 4275);
DISPLAY 0.872340 (-6175 4275);
DISPLAY INVISIBLE (-6175 4275);
FORCEPROP 1 LAST PATH I278
J 2
(-5848 4400);
DISPLAY 0.872340 (-5848 4400);
PAINT GREEN (-5848 4400);
DISPLAY INVISIBLE (-5848 4400);
FORCEADD TAP..1
R 2
(-5850 4300);
FORCEPROP 3 LASTPIN (-5800 4300) SIG_NAME M_L_CPU0_SB_DQS_DN<6>
J 0
(-5790 4310);
DISPLAY 0.659574 (-5790 4310);
PAINT MONO (-5790 4310);
DISPLAY INVISIBLE (-5790 4310);
FORCEPROP 1 LASTPIN (-5800 4300) BN 6
J 2
(-5788 4308);
DISPLAY 0.489362 (-5788 4308);
PAINT GREEN (-5788 4308);
FORCEPROP 2 LAST CDS_LIB mstr_standard
J 2
(-5850 4300);
DISPLAY 0.723404 (-5850 4300);
PAINT MONO (-5850 4300);
DISPLAY INVISIBLE (-5850 4300);
FORCEPROP 1 LAST BODY_TYPE PLUMBING
J 2
(-5850 4350);
DISPLAY 0.872340 (-5850 4350);
PAINT GREEN (-5850 4350);
DISPLAY INVISIBLE (-5850 4350);
FORCEPROP 1 LAST HDL_TAP TRUE
J 2
(-6175 4175);
DISPLAY 0.872340 (-6175 4175);
DISPLAY INVISIBLE (-6175 4175);
FORCEPROP 1 LAST PATH I279
J 2
(-5848 4300);
DISPLAY 0.872340 (-5848 4300);
PAINT GREEN (-5848 4300);
DISPLAY INVISIBLE (-5848 4300);
FORCEADD TAP..1
R 2
(-5850 4200);
FORCEPROP 3 LASTPIN (-5800 4200) SIG_NAME M_L_CPU0_SB_DQS_DN<7>
J 0
(-5790 4210);
DISPLAY 0.659574 (-5790 4210);
PAINT MONO (-5790 4210);
DISPLAY INVISIBLE (-5790 4210);
FORCEPROP 1 LASTPIN (-5800 4200) BN 7
J 2
(-5788 4208);
DISPLAY 0.489362 (-5788 4208);
PAINT GREEN (-5788 4208);
FORCEPROP 2 LAST CDS_LIB mstr_standard
J 2
(-5850 4200);
DISPLAY 0.723404 (-5850 4200);
PAINT MONO (-5850 4200);
DISPLAY INVISIBLE (-5850 4200);
FORCEPROP 1 LAST BODY_TYPE PLUMBING
J 2
(-5850 4250);
DISPLAY 0.872340 (-5850 4250);
PAINT GREEN (-5850 4250);
DISPLAY INVISIBLE (-5850 4250);
FORCEPROP 1 LAST HDL_TAP TRUE
J 2
(-6175 4075);
DISPLAY 0.872340 (-6175 4075);
DISPLAY INVISIBLE (-6175 4075);
FORCEPROP 1 LAST PATH I280
J 2
(-5848 4200);
DISPLAY 0.872340 (-5848 4200);
PAINT GREEN (-5848 4200);
DISPLAY INVISIBLE (-5848 4200);
FORCEADD TAP..1
R 2
(-5850 4100);
FORCEPROP 3 LASTPIN (-5800 4100) SIG_NAME M_L_CPU0_SB_DQS_DN<8>
J 0
(-5790 4110);
DISPLAY 0.659574 (-5790 4110);
PAINT MONO (-5790 4110);
DISPLAY INVISIBLE (-5790 4110);
FORCEPROP 1 LASTPIN (-5800 4100) BN 8
J 2
(-5788 4108);
DISPLAY 0.489362 (-5788 4108);
PAINT GREEN (-5788 4108);
FORCEPROP 2 LAST CDS_LIB mstr_standard
J 2
(-5850 4100);
DISPLAY 0.723404 (-5850 4100);
PAINT MONO (-5850 4100);
DISPLAY INVISIBLE (-5850 4100);
FORCEPROP 1 LAST BODY_TYPE PLUMBING
J 2
(-5850 4150);
DISPLAY 0.872340 (-5850 4150);
PAINT GREEN (-5850 4150);
DISPLAY INVISIBLE (-5850 4150);
FORCEPROP 1 LAST HDL_TAP TRUE
J 2
(-6175 3975);
DISPLAY 0.872340 (-6175 3975);
DISPLAY INVISIBLE (-6175 3975);
FORCEPROP 1 LAST PATH I281
J 2
(-5848 4100);
DISPLAY 0.872340 (-5848 4100);
PAINT GREEN (-5848 4100);
DISPLAY INVISIBLE (-5848 4100);
FORCEADD OFFPAGE..3
R 2
(-6550 6025);
FORCEPROP 2 LAST $XR0 96 
J 0
(-6799 6025);
DISPLAY 0.638298 (-6799 6025);
PAINT MONO (-6799 6025);
FORCEPROP 2 LAST PATH I282
J 0
(-6825 6075);
DISPLAY 1.021277 (-6825 6075);
DISPLAY INVISIBLE (-6825 6075);
FORCEPROP 1 LAST COMMENT_BODY TRUE
J 2
(-6500 5925);
DISPLAY 0.872340 (-6500 5925);
PAINT GREEN (-6500 5925);
DISPLAY INVISIBLE (-6500 5925);
FORCEPROP 1 LAST OFFPAGE TRUE
J 2
(-6875 5900);
DISPLAY 0.872340 (-6875 5900);
PAINT GREEN (-6875 5900);
DISPLAY INVISIBLE (-6875 5900);
FORCEPROP 2 LAST CDS_LIB standard
J 0
(-6550 6025);
DISPLAY INVISIBLE (-6550 6025);
FORCEADD OFFPAGE..3
R 2
(-6550 5975);
FORCEPROP 2 LAST $XR0 96 
J 0
(-6799 5975);
DISPLAY 0.638298 (-6799 5975);
PAINT MONO (-6799 5975);
FORCEPROP 2 LAST PATH I283
J 0
(-6825 6025);
DISPLAY 1.021277 (-6825 6025);
DISPLAY INVISIBLE (-6825 6025);
FORCEPROP 1 LAST COMMENT_BODY TRUE
J 2
(-6500 5875);
DISPLAY 0.872340 (-6500 5875);
PAINT GREEN (-6500 5875);
DISPLAY INVISIBLE (-6500 5875);
FORCEPROP 1 LAST OFFPAGE TRUE
J 2
(-6875 5850);
DISPLAY 0.872340 (-6875 5850);
PAINT GREEN (-6875 5850);
DISPLAY INVISIBLE (-6875 5850);
FORCEPROP 2 LAST CDS_LIB standard
J 0
(-6550 5975);
DISPLAY INVISIBLE (-6550 5975);
FORCEADD OFFPAGE..3
R 2
(-6550 4925);
FORCEPROP 2 LAST $XR0 96 
J 0
(-6799 4925);
DISPLAY 0.638298 (-6799 4925);
PAINT MONO (-6799 4925);
FORCEPROP 2 LAST PATH I284
J 0
(-6825 4975);
DISPLAY 1.021277 (-6825 4975);
DISPLAY INVISIBLE (-6825 4975);
FORCEPROP 1 LAST COMMENT_BODY TRUE
J 2
(-6500 4825);
DISPLAY 0.872340 (-6500 4825);
PAINT GREEN (-6500 4825);
DISPLAY INVISIBLE (-6500 4825);
FORCEPROP 1 LAST OFFPAGE TRUE
J 2
(-6875 4800);
DISPLAY 0.872340 (-6875 4800);
PAINT GREEN (-6875 4800);
DISPLAY INVISIBLE (-6875 4800);
FORCEPROP 2 LAST CDS_LIB standard
J 0
(-6550 4925);
DISPLAY INVISIBLE (-6550 4925);
FORCEADD OFFPAGE..3
R 2
(-6550 4975);
FORCEPROP 2 LAST $XR0 96 
J 0
(-6799 4975);
DISPLAY 0.638298 (-6799 4975);
PAINT MONO (-6799 4975);
FORCEPROP 2 LAST PATH I285
J 0
(-6825 5025);
DISPLAY 1.021277 (-6825 5025);
DISPLAY INVISIBLE (-6825 5025);
FORCEPROP 1 LAST COMMENT_BODY TRUE
J 2
(-6500 4875);
DISPLAY 0.872340 (-6500 4875);
PAINT GREEN (-6500 4875);
DISPLAY INVISIBLE (-6500 4875);
FORCEPROP 1 LAST OFFPAGE TRUE
J 2
(-6875 4850);
DISPLAY 0.872340 (-6875 4850);
PAINT GREEN (-6875 4850);
DISPLAY INVISIBLE (-6875 4850);
FORCEPROP 2 LAST CDS_LIB standard
J 0
(-6550 4975);
DISPLAY INVISIBLE (-6550 4975);
FORCEADD TAP..1
R 2
(-5650 4050);
FORCEPROP 3 LASTPIN (-5600 4050) SIG_NAME M_L_CPU0_SB_DQS_DP<9>
J 0
(-5590 4060);
DISPLAY 0.659574 (-5590 4060);
PAINT MONO (-5590 4060);
DISPLAY INVISIBLE (-5590 4060);
FORCEPROP 1 LASTPIN (-5600 4050) BN 9
J 2
(-5588 4058);
DISPLAY 0.489362 (-5588 4058);
PAINT GREEN (-5588 4058);
FORCEPROP 2 LAST CDS_LIB mstr_standard
J 2
(-5650 4050);
DISPLAY 0.723404 (-5650 4050);
PAINT MONO (-5650 4050);
DISPLAY INVISIBLE (-5650 4050);
FORCEPROP 1 LAST BODY_TYPE PLUMBING
J 2
(-5650 4100);
DISPLAY 0.872340 (-5650 4100);
PAINT GREEN (-5650 4100);
DISPLAY INVISIBLE (-5650 4100);
FORCEPROP 1 LAST HDL_TAP TRUE
J 2
(-5975 3925);
DISPLAY 0.872340 (-5975 3925);
DISPLAY INVISIBLE (-5975 3925);
FORCEPROP 1 LAST PATH I286
J 2
(-5648 4050);
DISPLAY 0.872340 (-5648 4050);
PAINT GREEN (-5648 4050);
DISPLAY INVISIBLE (-5648 4050);
FORCEADD TAP..1
R 2
(-5850 4000);
FORCEPROP 3 LASTPIN (-5800 4000) SIG_NAME M_L_CPU0_SB_DQS_DN<9>
J 0
(-5790 4010);
DISPLAY 0.659574 (-5790 4010);
PAINT MONO (-5790 4010);
DISPLAY INVISIBLE (-5790 4010);
FORCEPROP 1 LASTPIN (-5800 4000) BN 9
J 2
(-5788 4008);
DISPLAY 0.489362 (-5788 4008);
PAINT GREEN (-5788 4008);
FORCEPROP 2 LAST CDS_LIB mstr_standard
J 2
(-5850 4000);
DISPLAY 0.723404 (-5850 4000);
PAINT MONO (-5850 4000);
DISPLAY INVISIBLE (-5850 4000);
FORCEPROP 1 LAST BODY_TYPE PLUMBING
J 2
(-5850 4050);
DISPLAY 0.872340 (-5850 4050);
PAINT GREEN (-5850 4050);
DISPLAY INVISIBLE (-5850 4050);
FORCEPROP 1 LAST HDL_TAP TRUE
J 2
(-6175 3875);
DISPLAY 0.872340 (-6175 3875);
DISPLAY INVISIBLE (-6175 3875);
FORCEPROP 1 LAST PATH I287
J 2
(-5848 4000);
DISPLAY 0.872340 (-5848 4000);
PAINT GREEN (-5848 4000);
DISPLAY INVISIBLE (-5848 4000);
FORCEADD TAP..1
R 2
(-5850 3850);
FORCEPROP 3 LASTPIN (-5800 3850) SIG_NAME M_L_CPU0_SA_CA<0>
J 0
(-5790 3860);
DISPLAY 0.659574 (-5790 3860);
PAINT MONO (-5790 3860);
DISPLAY INVISIBLE (-5790 3860);
FORCEPROP 1 LASTPIN (-5800 3850) BN 0
J 2
(-5788 3858);
DISPLAY 0.489362 (-5788 3858);
PAINT GREEN (-5788 3858);
FORCEPROP 2 LAST CDS_LIB mstr_standard
J 0
(-5850 3850);
DISPLAY 0.723404 (-5850 3850);
PAINT MONO (-5850 3850);
DISPLAY INVISIBLE (-5850 3850);
FORCEPROP 1 LAST BODY_TYPE PLUMBING
J 2
(-5850 3900);
DISPLAY 0.872340 (-5850 3900);
PAINT GREEN (-5850 3900);
DISPLAY INVISIBLE (-5850 3900);
FORCEPROP 1 LAST HDL_TAP TRUE
J 2
(-6175 3725);
DISPLAY 0.872340 (-6175 3725);
DISPLAY INVISIBLE (-6175 3725);
FORCEPROP 1 LAST PATH I288
J 2
(-5848 3850);
DISPLAY 0.872340 (-5848 3850);
PAINT GREEN (-5848 3850);
DISPLAY INVISIBLE (-5848 3850);
FORCEADD TAP..1
R 2
(-5850 3750);
FORCEPROP 3 LASTPIN (-5800 3750) SIG_NAME M_L_CPU0_SA_CA<2>
J 0
(-5790 3760);
DISPLAY 0.659574 (-5790 3760);
PAINT MONO (-5790 3760);
DISPLAY INVISIBLE (-5790 3760);
FORCEPROP 1 LASTPIN (-5800 3750) BN 2
J 2
(-5788 3758);
DISPLAY 0.489362 (-5788 3758);
PAINT GREEN (-5788 3758);
FORCEPROP 2 LAST CDS_LIB mstr_standard
J 0
(-5850 3750);
DISPLAY 0.723404 (-5850 3750);
PAINT MONO (-5850 3750);
DISPLAY INVISIBLE (-5850 3750);
FORCEPROP 1 LAST BODY_TYPE PLUMBING
J 2
(-5850 3800);
DISPLAY 0.872340 (-5850 3800);
PAINT GREEN (-5850 3800);
DISPLAY INVISIBLE (-5850 3800);
FORCEPROP 1 LAST HDL_TAP TRUE
J 2
(-6175 3625);
DISPLAY 0.872340 (-6175 3625);
DISPLAY INVISIBLE (-6175 3625);
FORCEPROP 1 LAST PATH I289
J 2
(-5848 3750);
DISPLAY 0.872340 (-5848 3750);
PAINT GREEN (-5848 3750);
DISPLAY INVISIBLE (-5848 3750);
FORCEADD TAP..1
R 2
(-5850 3800);
FORCEPROP 3 LASTPIN (-5800 3800) SIG_NAME M_L_CPU0_SA_CA<1>
J 0
(-5790 3810);
DISPLAY 0.659574 (-5790 3810);
PAINT MONO (-5790 3810);
DISPLAY INVISIBLE (-5790 3810);
FORCEPROP 1 LASTPIN (-5800 3800) BN 1
J 2
(-5788 3808);
DISPLAY 0.489362 (-5788 3808);
PAINT GREEN (-5788 3808);
FORCEPROP 2 LAST CDS_LIB mstr_standard
J 0
(-5850 3800);
DISPLAY 0.723404 (-5850 3800);
PAINT MONO (-5850 3800);
DISPLAY INVISIBLE (-5850 3800);
FORCEPROP 1 LAST BODY_TYPE PLUMBING
J 2
(-5850 3850);
DISPLAY 0.872340 (-5850 3850);
PAINT GREEN (-5850 3850);
DISPLAY INVISIBLE (-5850 3850);
FORCEPROP 1 LAST HDL_TAP TRUE
J 2
(-6175 3675);
DISPLAY 0.872340 (-6175 3675);
DISPLAY INVISIBLE (-6175 3675);
FORCEPROP 1 LAST PATH I290
J 2
(-5848 3800);
DISPLAY 0.872340 (-5848 3800);
PAINT GREEN (-5848 3800);
DISPLAY INVISIBLE (-5848 3800);
FORCEADD TAP..1
R 2
(-5850 3700);
FORCEPROP 3 LASTPIN (-5800 3700) SIG_NAME M_L_CPU0_SA_CA<3>
J 0
(-5790 3710);
DISPLAY 0.659574 (-5790 3710);
PAINT MONO (-5790 3710);
DISPLAY INVISIBLE (-5790 3710);
FORCEPROP 1 LASTPIN (-5800 3700) BN 3
J 2
(-5788 3708);
DISPLAY 0.489362 (-5788 3708);
PAINT GREEN (-5788 3708);
FORCEPROP 2 LAST CDS_LIB mstr_standard
J 0
(-5850 3700);
DISPLAY 0.723404 (-5850 3700);
PAINT MONO (-5850 3700);
DISPLAY INVISIBLE (-5850 3700);
FORCEPROP 1 LAST BODY_TYPE PLUMBING
J 2
(-5850 3750);
DISPLAY 0.872340 (-5850 3750);
PAINT GREEN (-5850 3750);
DISPLAY INVISIBLE (-5850 3750);
FORCEPROP 1 LAST HDL_TAP TRUE
J 2
(-6175 3575);
DISPLAY 0.872340 (-6175 3575);
DISPLAY INVISIBLE (-6175 3575);
FORCEPROP 1 LAST PATH I291
J 2
(-5848 3700);
DISPLAY 0.872340 (-5848 3700);
PAINT GREEN (-5848 3700);
DISPLAY INVISIBLE (-5848 3700);
FORCEADD TAP..1
R 2
(-5850 3650);
FORCEPROP 3 LASTPIN (-5800 3650) SIG_NAME M_L_CPU0_SA_CA<4>
J 0
(-5790 3660);
DISPLAY 0.659574 (-5790 3660);
PAINT MONO (-5790 3660);
DISPLAY INVISIBLE (-5790 3660);
FORCEPROP 1 LASTPIN (-5800 3650) BN 4
J 2
(-5788 3658);
DISPLAY 0.489362 (-5788 3658);
PAINT GREEN (-5788 3658);
FORCEPROP 2 LAST CDS_LIB mstr_standard
J 0
(-5850 3650);
DISPLAY 0.723404 (-5850 3650);
PAINT MONO (-5850 3650);
DISPLAY INVISIBLE (-5850 3650);
FORCEPROP 1 LAST BODY_TYPE PLUMBING
J 2
(-5850 3700);
DISPLAY 0.872340 (-5850 3700);
PAINT GREEN (-5850 3700);
DISPLAY INVISIBLE (-5850 3700);
FORCEPROP 1 LAST HDL_TAP TRUE
J 2
(-6175 3525);
DISPLAY 0.872340 (-6175 3525);
DISPLAY INVISIBLE (-6175 3525);
FORCEPROP 1 LAST PATH I292
J 2
(-5848 3650);
DISPLAY 0.872340 (-5848 3650);
PAINT GREEN (-5848 3650);
DISPLAY INVISIBLE (-5848 3650);
FORCEADD TAP..1
R 2
(-5850 3600);
FORCEPROP 3 LASTPIN (-5800 3600) SIG_NAME M_L_CPU0_SA_CA<5>
J 0
(-5790 3610);
DISPLAY 0.659574 (-5790 3610);
PAINT MONO (-5790 3610);
DISPLAY INVISIBLE (-5790 3610);
FORCEPROP 1 LASTPIN (-5800 3600) BN 5
J 2
(-5788 3608);
DISPLAY 0.489362 (-5788 3608);
PAINT GREEN (-5788 3608);
FORCEPROP 2 LAST CDS_LIB mstr_standard
J 0
(-5850 3600);
DISPLAY 0.723404 (-5850 3600);
PAINT MONO (-5850 3600);
DISPLAY INVISIBLE (-5850 3600);
FORCEPROP 1 LAST BODY_TYPE PLUMBING
J 2
(-5850 3650);
DISPLAY 0.872340 (-5850 3650);
PAINT GREEN (-5850 3650);
DISPLAY INVISIBLE (-5850 3650);
FORCEPROP 1 LAST HDL_TAP TRUE
J 2
(-6175 3475);
DISPLAY 0.872340 (-6175 3475);
DISPLAY INVISIBLE (-6175 3475);
FORCEPROP 1 LAST PATH I293
J 2
(-5848 3600);
DISPLAY 0.872340 (-5848 3600);
PAINT GREEN (-5848 3600);
DISPLAY INVISIBLE (-5848 3600);
FORCEADD TAP..1
R 2
(-5850 3350);
FORCEPROP 3 LASTPIN (-5800 3350) SIG_NAME M_L_CPU0_SB_CA<2>
J 0
(-5790 3360);
DISPLAY 0.659574 (-5790 3360);
PAINT MONO (-5790 3360);
DISPLAY INVISIBLE (-5790 3360);
FORCEPROP 1 LASTPIN (-5800 3350) BN 2
J 2
(-5788 3358);
DISPLAY 0.489362 (-5788 3358);
PAINT GREEN (-5788 3358);
FORCEPROP 2 LAST CDS_LIB mstr_standard
J 0
(-5850 3350);
DISPLAY 0.723404 (-5850 3350);
PAINT MONO (-5850 3350);
DISPLAY INVISIBLE (-5850 3350);
FORCEPROP 1 LAST BODY_TYPE PLUMBING
J 2
(-5850 3400);
DISPLAY 0.872340 (-5850 3400);
PAINT GREEN (-5850 3400);
DISPLAY INVISIBLE (-5850 3400);
FORCEPROP 1 LAST HDL_TAP TRUE
J 2
(-6175 3225);
DISPLAY 0.872340 (-6175 3225);
DISPLAY INVISIBLE (-6175 3225);
FORCEPROP 1 LAST PATH I294
J 2
(-5848 3350);
DISPLAY 0.872340 (-5848 3350);
PAINT GREEN (-5848 3350);
DISPLAY INVISIBLE (-5848 3350);
FORCEADD TAP..1
R 2
(-5850 3550);
FORCEPROP 3 LASTPIN (-5800 3550) SIG_NAME M_L_CPU0_SA_CA<6>
J 0
(-5790 3560);
DISPLAY 0.659574 (-5790 3560);
PAINT MONO (-5790 3560);
DISPLAY INVISIBLE (-5790 3560);
FORCEPROP 1 LASTPIN (-5800 3550) BN 6
J 2
(-5788 3558);
DISPLAY 0.489362 (-5788 3558);
PAINT GREEN (-5788 3558);
FORCEPROP 2 LAST CDS_LIB mstr_standard
J 0
(-5850 3550);
DISPLAY 0.723404 (-5850 3550);
PAINT MONO (-5850 3550);
DISPLAY INVISIBLE (-5850 3550);
FORCEPROP 1 LAST BODY_TYPE PLUMBING
J 2
(-5850 3600);
DISPLAY 0.872340 (-5850 3600);
PAINT GREEN (-5850 3600);
DISPLAY INVISIBLE (-5850 3600);
FORCEPROP 1 LAST HDL_TAP TRUE
J 2
(-6175 3425);
DISPLAY 0.872340 (-6175 3425);
DISPLAY INVISIBLE (-6175 3425);
FORCEPROP 1 LAST PATH I295
J 2
(-5848 3550);
DISPLAY 0.872340 (-5848 3550);
PAINT GREEN (-5848 3550);
DISPLAY INVISIBLE (-5848 3550);
FORCEADD TAP..1
R 2
(-5850 3450);
FORCEPROP 3 LASTPIN (-5800 3450) SIG_NAME M_L_CPU0_SB_CA<0>
J 0
(-5790 3460);
DISPLAY 0.659574 (-5790 3460);
PAINT MONO (-5790 3460);
DISPLAY INVISIBLE (-5790 3460);
FORCEPROP 1 LASTPIN (-5800 3450) BN 0
J 2
(-5788 3458);
DISPLAY 0.489362 (-5788 3458);
PAINT GREEN (-5788 3458);
FORCEPROP 2 LAST CDS_LIB mstr_standard
J 0
(-5850 3450);
DISPLAY 0.723404 (-5850 3450);
PAINT MONO (-5850 3450);
DISPLAY INVISIBLE (-5850 3450);
FORCEPROP 1 LAST BODY_TYPE PLUMBING
J 2
(-5850 3500);
DISPLAY 0.872340 (-5850 3500);
PAINT GREEN (-5850 3500);
DISPLAY INVISIBLE (-5850 3500);
FORCEPROP 1 LAST HDL_TAP TRUE
J 2
(-6175 3325);
DISPLAY 0.872340 (-6175 3325);
DISPLAY INVISIBLE (-6175 3325);
FORCEPROP 1 LAST PATH I296
J 2
(-5848 3450);
DISPLAY 0.872340 (-5848 3450);
PAINT GREEN (-5848 3450);
DISPLAY INVISIBLE (-5848 3450);
FORCEADD TAP..1
R 2
(-5850 3400);
FORCEPROP 3 LASTPIN (-5800 3400) SIG_NAME M_L_CPU0_SB_CA<1>
J 0
(-5790 3410);
DISPLAY 0.659574 (-5790 3410);
PAINT MONO (-5790 3410);
DISPLAY INVISIBLE (-5790 3410);
FORCEPROP 1 LASTPIN (-5800 3400) BN 1
J 2
(-5788 3408);
DISPLAY 0.489362 (-5788 3408);
PAINT GREEN (-5788 3408);
FORCEPROP 2 LAST CDS_LIB mstr_standard
J 0
(-5850 3400);
DISPLAY 0.723404 (-5850 3400);
PAINT MONO (-5850 3400);
DISPLAY INVISIBLE (-5850 3400);
FORCEPROP 1 LAST BODY_TYPE PLUMBING
J 2
(-5850 3450);
DISPLAY 0.872340 (-5850 3450);
PAINT GREEN (-5850 3450);
DISPLAY INVISIBLE (-5850 3450);
FORCEPROP 1 LAST HDL_TAP TRUE
J 2
(-6175 3275);
DISPLAY 0.872340 (-6175 3275);
DISPLAY INVISIBLE (-6175 3275);
FORCEPROP 1 LAST PATH I297
J 2
(-5848 3400);
DISPLAY 0.872340 (-5848 3400);
PAINT GREEN (-5848 3400);
DISPLAY INVISIBLE (-5848 3400);
FORCEADD TAP..1
R 2
(-5850 3200);
FORCEPROP 3 LASTPIN (-5800 3200) SIG_NAME M_L_CPU0_SB_CA<5>
J 0
(-5790 3210);
DISPLAY 0.659574 (-5790 3210);
PAINT MONO (-5790 3210);
DISPLAY INVISIBLE (-5790 3210);
FORCEPROP 1 LASTPIN (-5800 3200) BN 5
J 2
(-5788 3208);
DISPLAY 0.489362 (-5788 3208);
PAINT GREEN (-5788 3208);
FORCEPROP 2 LAST CDS_LIB mstr_standard
J 0
(-5850 3200);
DISPLAY 0.723404 (-5850 3200);
PAINT MONO (-5850 3200);
DISPLAY INVISIBLE (-5850 3200);
FORCEPROP 1 LAST BODY_TYPE PLUMBING
J 2
(-5850 3250);
DISPLAY 0.872340 (-5850 3250);
PAINT GREEN (-5850 3250);
DISPLAY INVISIBLE (-5850 3250);
FORCEPROP 1 LAST HDL_TAP TRUE
J 2
(-6175 3075);
DISPLAY 0.872340 (-6175 3075);
DISPLAY INVISIBLE (-6175 3075);
FORCEPROP 1 LAST PATH I298
J 2
(-5848 3200);
DISPLAY 0.872340 (-5848 3200);
PAINT GREEN (-5848 3200);
DISPLAY INVISIBLE (-5848 3200);
FORCEADD TAP..1
R 2
(-5850 3300);
FORCEPROP 3 LASTPIN (-5800 3300) SIG_NAME M_L_CPU0_SB_CA<3>
J 0
(-5790 3310);
DISPLAY 0.659574 (-5790 3310);
PAINT MONO (-5790 3310);
DISPLAY INVISIBLE (-5790 3310);
FORCEPROP 1 LASTPIN (-5800 3300) BN 3
J 2
(-5788 3308);
DISPLAY 0.489362 (-5788 3308);
PAINT GREEN (-5788 3308);
FORCEPROP 2 LAST CDS_LIB mstr_standard
J 0
(-5850 3300);
DISPLAY 0.723404 (-5850 3300);
PAINT MONO (-5850 3300);
DISPLAY INVISIBLE (-5850 3300);
FORCEPROP 1 LAST BODY_TYPE PLUMBING
J 2
(-5850 3350);
DISPLAY 0.872340 (-5850 3350);
PAINT GREEN (-5850 3350);
DISPLAY INVISIBLE (-5850 3350);
FORCEPROP 1 LAST HDL_TAP TRUE
J 2
(-6175 3175);
DISPLAY 0.872340 (-6175 3175);
DISPLAY INVISIBLE (-6175 3175);
FORCEPROP 1 LAST PATH I299
J 2
(-5848 3300);
DISPLAY 0.872340 (-5848 3300);
PAINT GREEN (-5848 3300);
DISPLAY INVISIBLE (-5848 3300);
FORCEADD TAP..1
R 2
(-5850 3250);
FORCEPROP 3 LASTPIN (-5800 3250) SIG_NAME M_L_CPU0_SB_CA<4>
J 0
(-5790 3260);
DISPLAY 0.659574 (-5790 3260);
PAINT MONO (-5790 3260);
DISPLAY INVISIBLE (-5790 3260);
FORCEPROP 1 LASTPIN (-5800 3250) BN 4
J 2
(-5788 3258);
DISPLAY 0.489362 (-5788 3258);
PAINT GREEN (-5788 3258);
FORCEPROP 2 LAST CDS_LIB mstr_standard
J 0
(-5850 3250);
DISPLAY 0.723404 (-5850 3250);
PAINT MONO (-5850 3250);
DISPLAY INVISIBLE (-5850 3250);
FORCEPROP 1 LAST BODY_TYPE PLUMBING
J 2
(-5850 3300);
DISPLAY 0.872340 (-5850 3300);
PAINT GREEN (-5850 3300);
DISPLAY INVISIBLE (-5850 3300);
FORCEPROP 1 LAST HDL_TAP TRUE
J 2
(-6175 3125);
DISPLAY 0.872340 (-6175 3125);
DISPLAY INVISIBLE (-6175 3125);
FORCEPROP 1 LAST PATH I300
J 2
(-5848 3250);
DISPLAY 0.872340 (-5848 3250);
PAINT GREEN (-5848 3250);
DISPLAY INVISIBLE (-5848 3250);
FORCEADD TAP..1
R 2
(-5850 3150);
FORCEPROP 3 LASTPIN (-5800 3150) SIG_NAME M_L_CPU0_SB_CA<6>
J 0
(-5790 3160);
DISPLAY 0.659574 (-5790 3160);
PAINT MONO (-5790 3160);
DISPLAY INVISIBLE (-5790 3160);
FORCEPROP 1 LASTPIN (-5800 3150) BN 6
J 2
(-5788 3158);
DISPLAY 0.489362 (-5788 3158);
PAINT GREEN (-5788 3158);
FORCEPROP 2 LAST CDS_LIB mstr_standard
J 0
(-5850 3150);
DISPLAY 0.723404 (-5850 3150);
PAINT MONO (-5850 3150);
DISPLAY INVISIBLE (-5850 3150);
FORCEPROP 1 LAST BODY_TYPE PLUMBING
J 2
(-5850 3200);
DISPLAY 0.872340 (-5850 3200);
PAINT GREEN (-5850 3200);
DISPLAY INVISIBLE (-5850 3200);
FORCEPROP 1 LAST HDL_TAP TRUE
J 2
(-6175 3025);
DISPLAY 0.872340 (-6175 3025);
DISPLAY INVISIBLE (-6175 3025);
FORCEPROP 1 LAST PATH I301
J 2
(-5848 3150);
DISPLAY 0.872340 (-5848 3150);
PAINT GREEN (-5848 3150);
DISPLAY INVISIBLE (-5848 3150);
FORCEADD OFFPAGE..2
R 2
(-6450 3875);
FORCEPROP 2 LAST $XR0 96 
J 0
(-6674 3875);
DISPLAY 0.638298 (-6674 3875);
PAINT MONO (-6674 3875);
FORCEPROP 2 LAST PATH I302
J 0
(-6700 3925);
DISPLAY 1.021277 (-6700 3925);
DISPLAY INVISIBLE (-6700 3925);
FORCEPROP 1 LAST COMMENT_BODY TRUE
J 2
(-6405 3780);
DISPLAY 0.872340 (-6405 3780);
PAINT GREEN (-6405 3780);
DISPLAY INVISIBLE (-6405 3780);
FORCEPROP 1 LAST OFFPAGE TRUE
J 2
(-6775 3750);
DISPLAY 0.872340 (-6775 3750);
PAINT GREEN (-6775 3750);
DISPLAY INVISIBLE (-6775 3750);
FORCEPROP 2 LAST CDS_LIB standard
J 0
(-6450 3875);
DISPLAY INVISIBLE (-6450 3875);
FORCEADD OFFPAGE..2
R 2
(-6450 3475);
FORCEPROP 2 LAST $XR0 96 
J 0
(-6674 3475);
DISPLAY 0.638298 (-6674 3475);
PAINT MONO (-6674 3475);
FORCEPROP 2 LAST PATH I303
J 0
(-6700 3525);
DISPLAY 1.021277 (-6700 3525);
DISPLAY INVISIBLE (-6700 3525);
FORCEPROP 1 LAST COMMENT_BODY TRUE
J 2
(-6405 3380);
DISPLAY 0.872340 (-6405 3380);
PAINT GREEN (-6405 3380);
DISPLAY INVISIBLE (-6405 3380);
FORCEPROP 1 LAST OFFPAGE TRUE
J 2
(-6775 3350);
DISPLAY 0.872340 (-6775 3350);
PAINT GREEN (-6775 3350);
DISPLAY INVISIBLE (-6775 3350);
FORCEPROP 2 LAST CDS_LIB standard
J 0
(-6450 3475);
DISPLAY INVISIBLE (-6450 3475);
FORCEADD OFFPAGE..2
R 2
(-6450 3000);
FORCEPROP 2 LAST $XR0 96 
J 0
(-6674 3000);
DISPLAY 0.638298 (-6674 3000);
PAINT MONO (-6674 3000);
FORCEPROP 2 LAST PATH I304
J 0
(-6700 3050);
DISPLAY 1.021277 (-6700 3050);
DISPLAY INVISIBLE (-6700 3050);
FORCEPROP 1 LAST COMMENT_BODY TRUE
J 2
(-6405 2905);
DISPLAY 0.872340 (-6405 2905);
PAINT GREEN (-6405 2905);
DISPLAY INVISIBLE (-6405 2905);
FORCEPROP 1 LAST OFFPAGE TRUE
J 2
(-6775 2875);
DISPLAY 0.872340 (-6775 2875);
PAINT GREEN (-6775 2875);
DISPLAY INVISIBLE (-6775 2875);
FORCEPROP 2 LAST CDS_LIB standard
J 0
(-6450 3000);
DISPLAY INVISIBLE (-6450 3000);
FORCEADD OFFPAGE..2
R 2
(-6450 2950);
FORCEPROP 2 LAST $XR0 96 
J 0
(-6674 2950);
DISPLAY 0.638298 (-6674 2950);
PAINT MONO (-6674 2950);
FORCEPROP 2 LAST PATH I305
J 0
(-6700 3000);
DISPLAY 1.021277 (-6700 3000);
DISPLAY INVISIBLE (-6700 3000);
FORCEPROP 1 LAST COMMENT_BODY TRUE
J 2
(-6405 2855);
DISPLAY 0.872340 (-6405 2855);
PAINT GREEN (-6405 2855);
DISPLAY INVISIBLE (-6405 2855);
FORCEPROP 1 LAST OFFPAGE TRUE
J 2
(-6775 2825);
DISPLAY 0.872340 (-6775 2825);
PAINT GREEN (-6775 2825);
DISPLAY INVISIBLE (-6775 2825);
FORCEPROP 2 LAST CDS_LIB standard
J 0
(-6450 2950);
DISPLAY INVISIBLE (-6450 2950);
FORCEADD OFFPAGE..2
R 2
(-6450 2850);
FORCEPROP 2 LAST $XR0 96 
J 0
(-6674 2850);
DISPLAY 0.638298 (-6674 2850);
PAINT MONO (-6674 2850);
FORCEPROP 2 LAST PATH I306
J 0
(-6700 2900);
DISPLAY 1.021277 (-6700 2900);
DISPLAY INVISIBLE (-6700 2900);
FORCEPROP 1 LAST COMMENT_BODY TRUE
J 2
(-6405 2755);
DISPLAY 0.872340 (-6405 2755);
PAINT GREEN (-6405 2755);
DISPLAY INVISIBLE (-6405 2755);
FORCEPROP 1 LAST OFFPAGE TRUE
J 2
(-6775 2725);
DISPLAY 0.872340 (-6775 2725);
PAINT GREEN (-6775 2725);
DISPLAY INVISIBLE (-6775 2725);
FORCEPROP 2 LAST CDS_LIB standard
J 0
(-6450 2850);
DISPLAY INVISIBLE (-6450 2850);
FORCEADD OFFPAGE..5
(-6450 2600);
FORCEPROP 2 LAST $XR0 96 
J 0
(-6674 2600);
DISPLAY 0.638298 (-6674 2600);
PAINT MONO (-6674 2600);
FORCEPROP 2 LAST PATH I307
J 0
(-6700 2650);
DISPLAY 1.021277 (-6700 2650);
DISPLAY INVISIBLE (-6700 2650);
FORCEPROP 1 LAST COMMENT_BODY TRUE
J 0
(-6350 2525);
DISPLAY 0.872340 (-6350 2525);
PAINT GREEN (-6350 2525);
DISPLAY INVISIBLE (-6350 2525);
FORCEPROP 1 LAST OFFPAGE TRUE
J 0
(-6125 2475);
DISPLAY 0.872340 (-6125 2475);
PAINT GREEN (-6125 2475);
DISPLAY INVISIBLE (-6125 2475);
FORCEPROP 2 LAST CDS_LIB mstr_standard
J 0
(-6450 2600);
DISPLAY INVISIBLE (-6450 2600);
FORCEADD OFFPAGE..1
(-6450 2700);
FORCEPROP 2 LAST $XR0 96 
J 0
(-6701 2700);
DISPLAY 0.638298 (-6701 2700);
PAINT MONO (-6701 2700);
FORCEPROP 2 LAST PATH I308
J 0
(-6725 2750);
DISPLAY 1.021277 (-6725 2750);
DISPLAY INVISIBLE (-6725 2750);
FORCEPROP 1 LAST COMMENT_BODY TRUE
J 0
(-6325 2600);
DISPLAY 0.872340 (-6325 2600);
PAINT GREEN (-6325 2600);
DISPLAY INVISIBLE (-6325 2600);
FORCEPROP 1 LAST OFFPAGE TRUE
J 0
(-6125 2575);
DISPLAY 0.872340 (-6125 2575);
PAINT GREEN (-6125 2575);
DISPLAY INVISIBLE (-6125 2575);
FORCEPROP 2 LAST CDS_LIB standard
J 0
(-6450 2700);
DISPLAY INVISIBLE (-6450 2700);
FORCEADD OFFPAGE..2
R 2
(-6450 2800);
FORCEPROP 2 LAST $XR0 96 
J 0
(-6674 2800);
DISPLAY 0.638298 (-6674 2800);
PAINT MONO (-6674 2800);
FORCEPROP 2 LAST PATH I309
J 0
(-6700 2850);
DISPLAY 1.021277 (-6700 2850);
DISPLAY INVISIBLE (-6700 2850);
FORCEPROP 1 LAST COMMENT_BODY TRUE
J 2
(-6405 2705);
DISPLAY 0.872340 (-6405 2705);
PAINT GREEN (-6405 2705);
DISPLAY INVISIBLE (-6405 2705);
FORCEPROP 1 LAST OFFPAGE TRUE
J 2
(-6775 2675);
DISPLAY 0.872340 (-6775 2675);
PAINT GREEN (-6775 2675);
DISPLAY INVISIBLE (-6775 2675);
FORCEPROP 2 LAST CDS_LIB standard
J 0
(-6450 2800);
DISPLAY INVISIBLE (-6450 2800);
FORCEADD OFFPAGE..2
R 2
(-6450 2500);
FORCEPROP 2 LAST $XR0 96 
J 0
(-6674 2500);
DISPLAY 0.638298 (-6674 2500);
PAINT MONO (-6674 2500);
FORCEPROP 2 LAST PATH I310
J 0
(-6700 2550);
DISPLAY 1.021277 (-6700 2550);
DISPLAY INVISIBLE (-6700 2550);
FORCEPROP 1 LAST COMMENT_BODY TRUE
J 2
(-6405 2405);
DISPLAY 0.872340 (-6405 2405);
PAINT GREEN (-6405 2405);
DISPLAY INVISIBLE (-6405 2405);
FORCEPROP 1 LAST OFFPAGE TRUE
J 2
(-6775 2375);
DISPLAY 0.872340 (-6775 2375);
PAINT GREEN (-6775 2375);
DISPLAY INVISIBLE (-6775 2375);
FORCEPROP 2 LAST CDS_LIB standard
J 0
(-6450 2500);
DISPLAY INVISIBLE (-6450 2500);
FORCEADD OFFPAGE..2
R 2
(-6450 2450);
FORCEPROP 2 LAST $XR0 96 
J 0
(-6674 2450);
DISPLAY 0.638298 (-6674 2450);
PAINT MONO (-6674 2450);
FORCEPROP 2 LAST PATH I311
J 0
(-6700 2500);
DISPLAY 1.021277 (-6700 2500);
DISPLAY INVISIBLE (-6700 2500);
FORCEPROP 1 LAST COMMENT_BODY TRUE
J 2
(-6405 2355);
DISPLAY 0.872340 (-6405 2355);
PAINT GREEN (-6405 2355);
DISPLAY INVISIBLE (-6405 2355);
FORCEPROP 1 LAST OFFPAGE TRUE
J 2
(-6775 2325);
DISPLAY 0.872340 (-6775 2325);
PAINT GREEN (-6775 2325);
DISPLAY INVISIBLE (-6775 2325);
FORCEPROP 2 LAST CDS_LIB standard
J 0
(-6450 2450);
DISPLAY INVISIBLE (-6450 2450);
FORCEADD OFFPAGE..1
(-6450 2350);
FORCEPROP 2 LAST $XR0 96 
J 0
(-6701 2350);
DISPLAY 0.638298 (-6701 2350);
PAINT MONO (-6701 2350);
FORCEPROP 2 LAST PATH I312
J 0
(-6725 2400);
DISPLAY 1.021277 (-6725 2400);
DISPLAY INVISIBLE (-6725 2400);
FORCEPROP 1 LAST COMMENT_BODY TRUE
J 0
(-6325 2250);
DISPLAY 0.872340 (-6325 2250);
PAINT GREEN (-6325 2250);
DISPLAY INVISIBLE (-6325 2250);
FORCEPROP 1 LAST OFFPAGE TRUE
J 0
(-6125 2225);
DISPLAY 0.872340 (-6125 2225);
PAINT GREEN (-6125 2225);
DISPLAY INVISIBLE (-6125 2225);
FORCEPROP 2 LAST CDS_LIB standard
J 0
(-6450 2350);
DISPLAY INVISIBLE (-6450 2350);
FORCEADD OFFPAGE..5
(-6450 2250);
FORCEPROP 2 LAST $XR0 96 
J 0
(-6674 2250);
DISPLAY 0.638298 (-6674 2250);
PAINT MONO (-6674 2250);
FORCEPROP 2 LAST PATH I313
J 0
(-6700 2300);
DISPLAY 1.021277 (-6700 2300);
DISPLAY INVISIBLE (-6700 2300);
FORCEPROP 1 LAST COMMENT_BODY TRUE
J 0
(-6350 2175);
DISPLAY 0.872340 (-6350 2175);
PAINT GREEN (-6350 2175);
DISPLAY INVISIBLE (-6350 2175);
FORCEPROP 1 LAST OFFPAGE TRUE
J 0
(-6125 2125);
DISPLAY 0.872340 (-6125 2125);
PAINT GREEN (-6125 2125);
DISPLAY INVISIBLE (-6125 2125);
FORCEPROP 2 LAST CDS_LIB standard
J 0
(-6450 2250);
DISPLAY INVISIBLE (-6450 2250);
FORCEADD Q_RES..1
(-6775 2150);
FORCEPROP 1 LAST LOCATION R386
J 0
(-7100 2150);
DISPLAY 0.489362 (-7100 2150);
PAINT SKYBLUE (-7100 2150);
FORCEPROP 0 LAST $SEC 1
J 0
(-6950 2200);
DISPLAY 0.680851 (-6950 2200);
PAINT MONO (-6950 2200);
DISPLAY INVISIBLE (-6950 2200);
FORCEPROP 0 LAST CDS_SEC 1
J 0
(-6950 2200);
DISPLAY 1.021277 (-6950 2200);
DISPLAY INVISIBLE (-6950 2200);
FORCEPROP 1 LASTPIN (-6875 2150) $PN 1
J 0
(-6863 2162);
DISPLAY 0.489362 (-6863 2162);
PAINT MONO (-6863 2162);
FORCEPROP 1 LASTPIN (-6675 2150) $PN 2
J 0
(-6713 2162);
DISPLAY 0.489362 (-6713 2162);
PAINT MONO (-6713 2162);
FORCEPROP 1 LAST TOLERANCE 1%
J 0
(-6500 2150);
DISPLAY 0.489362 (-6500 2150);
PAINT SKYBLUE (-6500 2150);
FORCEPROP 1 LAST VALUE 15   
J 2
(-6450 2150);
DISPLAY 0.489362 (-6450 2150);
PAINT SKYBLUE (-6450 2150);
FORCEPROP 1 LAST PART_NUMBER CS01502FB11
J 0
(-6625 2125);
DISPLAY 0.489362 (-6625 2125);
PAINT SKYBLUE (-6625 2125);
FORCEPROP 1 LAST PACK_TYPE 0402LF
J 0
(-7100 2125);
DISPLAY 0.489362 (-7100 2125);
PAINT SKYBLUE (-7100 2125);
FORCEPROP 2 LAST CDS_LIB pure_quanta
J 0
(-6775 2150);
DISPLAY INVISIBLE (-6775 2150);
FORCEPROP 1 LAST PATH I314
J 0
(-6825 2300);
DISPLAY 0.978723 (-6825 2300);
PAINT WHITE (-6825 2300);
DISPLAY INVISIBLE (-6825 2300);
FORCEPROP 1 LAST WATTAGE 1/16W
J 2
(-6550 2275);
DISPLAY 0.638298 (-6550 2275);
PAINT SKYBLUE (-6550 2275);
DISPLAY INVISIBLE (-6550 2275);
FORCEPROP 1 LAST MATERIAL CHIP
J 0
(-6900 2275);
DISPLAY 0.638298 (-6900 2275);
PAINT SKYBLUE (-6900 2275);
DISPLAY INVISIBLE (-6900 2275);
FORCEADD OFFPAGE..1
(-7650 2150);
FORCEPROP 2 LAST $XR0 96 
J 0
(-7871 2150);
DISPLAY 0.638298 (-7871 2150);
PAINT MONO (-7871 2150);
FORCEPROP 2 LAST PATH I315
J 0
(-7900 2200);
DISPLAY 1.021277 (-7900 2200);
DISPLAY INVISIBLE (-7900 2200);
FORCEPROP 1 LAST COMMENT_BODY TRUE
J 0
(-7525 2050);
DISPLAY 0.872340 (-7525 2050);
PAINT GREEN (-7525 2050);
DISPLAY INVISIBLE (-7525 2050);
FORCEPROP 1 LAST OFFPAGE TRUE
J 0
(-7325 2025);
DISPLAY 0.872340 (-7325 2025);
PAINT GREEN (-7325 2025);
DISPLAY INVISIBLE (-7325 2025);
FORCEPROP 2 LAST CDS_LIB mstr_standard
J 0
(-7650 2150);
DISPLAY INVISIBLE (-7650 2150);
FORCEADD OFFPAGE..5
(-6450 2050);
FORCEPROP 2 LAST $XR0 96 
J 0
(-6674 2050);
DISPLAY 0.638298 (-6674 2050);
PAINT MONO (-6674 2050);
FORCEPROP 2 LAST PATH I316
J 0
(-6700 2100);
DISPLAY 1.021277 (-6700 2100);
DISPLAY INVISIBLE (-6700 2100);
FORCEPROP 1 LAST COMMENT_BODY TRUE
J 0
(-6350 1975);
DISPLAY 0.872340 (-6350 1975);
PAINT GREEN (-6350 1975);
DISPLAY INVISIBLE (-6350 1975);
FORCEPROP 1 LAST OFFPAGE TRUE
J 0
(-6125 1925);
DISPLAY 0.872340 (-6125 1925);
PAINT GREEN (-6125 1925);
DISPLAY INVISIBLE (-6125 1925);
FORCEPROP 2 LAST CDS_LIB standard
J 0
(-6450 2050);
DISPLAY INVISIBLE (-6450 2050);
FORCEADD QUANTA_TITLE_BLOCK_C..1
(0 0);
FORCEPROP 0 LAST CDS_CON_LAST_MODIFIED Fri Mar 11 14:52:17 2022
J 0
(-1885 15);
DISPLAY INVISIBLE (-1885 15);
FORCEPROP 1 LAST CUSTOM_TXT_CDS <CON_LAST_MODIFIED>
J 0
(-1885 15);
DISPLAY 0.978723 (-1885 15);
FORCEPROP 2 LAST CUSTOM_TXT_CDS <XR_PAGE_TITLE>
J 0
(-7890 5250);
DISPLAY 0.638298 (-7890 5250);
PAINT PINK (-7890 5250);
DISPLAY INVISIBLE (-7890 5250);
FORCEPROP 1 LAST CUSTOM_TXT_CDS <NAME_2>
J 0
(-3175 50);
FORCEPROP 1 LAST CUSTOM_TXT_CDS <NAME_1>
J 0
(-3175 175);
FORCEPROP 1 LAST CUSTOM_TXT_CDS <Q_NUMBER>
J 0
(-1403 103);
DISPLAY 1.212766 (-1403 103);
FORCEPROP 1 LAST CUSTOM_TXT_CDS <Q_PROJ>
J 0
(-2382 102);
DISPLAY 1.212766 (-2382 102);
FORCEPROP 1 LAST CUSTOM_TXT_CDS <Q_REV>
J 0
(-184 103);
DISPLAY 1.212766 (-184 103);
FORCEPROP 1 LAST CUSTOM_TXT_CDS <CON_PAGE_NUM> OF <CON_TOTAL_PAGES>
J 0
(-446 18);
DISPLAY 0.978723 (-446 18);
FORCEPROP 1 LAST Q_TITLE CPU0 DDR CHL
J 0
(-9350 25);
DISPLAY 2.446809 (-9350 25);
PAINT GREEN (-9350 25);
FORCEPROP 1 LAST Q_DEPT BU9
J 1
(-3763 49);
DISPLAY 1.957447 (-3763 49);
PAINT GREEN (-3763 49);
FORCEPROP 2 LAST PAGE_BORDER TRUE
J 0
(-7890 5250);
DISPLAY 0.638298 (-7890 5250);
PAINT PINK (-7890 5250);
DISPLAY INVISIBLE (-7890 5250);
FORCEPROP 2 LAST CDS_LIB pure_quanta
J 0
(0 0);
DISPLAY INVISIBLE (0 0);
FORCEPROP 1 LAST CDS_LMAN_SYM_OUTLINE -9475,6775,100,-125
J 0
(0 0);
DISPLAY 0.468085 (0 0);
PAINT GREEN (0 0);
DISPLAY INVISIBLE (0 0);
FORCEPROP 1 LAST COMMENT_BODY TRUE
J 0
(12 -13);
DISPLAY 0.978723 (12 -13);
PAINT GREEN (12 -13);
DISPLAY INVISIBLE (12 -13);
FORCEPROP 2 LAST CDS_XR_PAGE_TITLE CR-21 : @T6G_MB_LIB.T6G(SCH_1):PAGE21
J 0
(-7890 5250);
DISPLAY 0.638298 (-7890 5250);
PAINT PINK (-7890 5250);
DISPLAY INVISIBLE (-7890 5250);
FORCEADD CAD_NOTE..1
(-7625 2450);
FORCEPROP 0 LAST L1 R1982 PLACE CLOSE TO CPU < 25MM
J 0
(-7775 2325);
DISPLAY 0.617021 (-7775 2325);
PAINT WHITE (-7775 2325);
FORCEPROP 2 LAST CDS_LIB pure_quanta_power
J 0
(-7625 2450);
DISPLAY INVISIBLE (-7625 2450);
FORCEPROP 1 LAST COMMENT_BODY TRUE
J 0
(-7600 2550);
DISPLAY 0.574468 (-7600 2550);
PAINT WHITE (-7600 2550);
DISPLAY INVISIBLE (-7600 2550);
WIRE 17 -1 (-3175 5425)(-3175 5375);
WIRE 17 -1 (-3175 5475)(-3175 5425);
WIRE 17 -1 (-3175 5375)(-3175 5325);
WIRE 17 -1 (-3175 5325)(-3175 5275);
WIRE 17 -1 (-3175 5525)(-3175 5475);
WIRE 17 -1 (-3175 5575)(-3175 5525);
WIRE 17 -1 (-3175 5275)(-3175 5225);
WIRE 17 -1 (-3175 5125)(-3175 5225);
WIRE 17 -1 (-3175 5675)(-3175 5575);
WIRE 17 -1 (-3175 5725)(-3175 5675);
WIRE 17 -1 (-3175 5075)(-3175 5125);
WIRE 17 -1 (-3175 5025)(-3175 5075);
WIRE 17 -1 (-3175 5775)(-3175 5725);
WIRE 17 -1 (-3175 5825)(-3175 5775);
WIRE 17 -1 (-3175 4975)(-3175 5025);
WIRE 17 -1 (-3175 4975)(-3175 4925);
WIRE 17 -1 (-3175 5875)(-3175 5825);
WIRE 17 -1 (-3175 5925)(-3175 5875);
WIRE 17 -1 (-3175 4925)(-3175 4875);
WIRE 17 -1 (-3175 4875)(-3175 4825);
WIRE 17 -1 (-3175 5975)(-3175 5925);
WIRE 17 -1 (-3175 6025)(-3175 5975);
WIRE 17 -1 (-3175 4825)(-3175 4775);
WIRE 17 -1 (-3175 4775)(-3175 4675);
WIRE 17 -1 (-3175 6025)(-2550 6025);
FORCEPROP 2 LAST SIG_NAME M_L_CPU0_SA_DQ<31:0>
J 2
(-2610 6035);
DISPLAY 0.489362 (-2610 6035);
WIRE 17 -1 (-3175 4675)(-3175 4625);
WIRE 17 -1 (-3175 4625)(-3175 4575);
WIRE 17 -1 (-3175 4575)(-3175 4525);
WIRE 17 -1 (-3175 4475)(-3175 4525);
WIRE 17 -1 (-3175 4425)(-3175 4475);
WIRE 17 -1 (-3175 4375)(-3175 4425);
WIRE 17 -1 (-3175 4325)(-3175 4375);
WIRE 17 -1 (-3175 4225)(-3175 4175);
WIRE 17 -1 (-3175 4225)(-2550 4225);
FORCEPROP 2 LAST SIG_NAME M_L_CPU0_SB_DQ<31:0>
J 2
(-2610 4235);
DISPLAY 0.489362 (-2610 4235);
WIRE 17 -1 (-3175 4175)(-3175 4125);
WIRE 17 -1 (-3175 4125)(-3175 4075);
WIRE 17 -1 (-3175 4075)(-3175 4025);
WIRE 17 -1 (-3175 4025)(-3175 3975);
WIRE 17 -1 (-3175 3975)(-3175 3925);
WIRE 17 -1 (-3175 3925)(-3175 3875);
WIRE 17 -1 (-3175 3875)(-3175 3775);
WIRE 17 -1 (-3175 3775)(-3175 3725);
WIRE 17 -1 (-3175 3725)(-3175 3675);
WIRE 17 -1 (-3175 3675)(-3175 3625);
WIRE 17 -1 (-3175 3625)(-3175 3575);
WIRE 17 -1 (-3175 3575)(-3175 3525);
WIRE 17 -1 (-3175 3525)(-3175 3475);
WIRE 17 -1 (-3175 3475)(-3175 3425);
WIRE 17 -1 (-3175 3325)(-3175 3425);
WIRE 17 -1 (-3175 3125)(-3175 3075);
WIRE 17 -1 (-3175 3175)(-3175 3125);
WIRE 17 -1 (-3175 3075)(-3175 3025);
WIRE 17 -1 (-3175 3025)(-3175 2975);
WIRE 17 -1 (-3175 3175)(-3175 3225);
WIRE 17 -1 (-3175 3225)(-3175 3275);
WIRE 17 -1 (-3175 2975)(-3175 2875);
WIRE 17 -1 (-3175 2875)(-3175 2825);
WIRE 17 -1 (-3175 3275)(-3175 3325);
WIRE 17 -1 (-3175 2825)(-3175 2775);
WIRE 17 -1 (-3175 2775)(-3175 2725);
WIRE 17 -1 (-3175 2675)(-3175 2725);
WIRE 17 -1 (-3175 2625)(-3175 2675);
WIRE 17 -1 (-3175 2575)(-3175 2625);
WIRE 17 -1 (-3175 2525)(-3175 2575);
WIRE 17 -1 (-3175 2325)(-3175 2275);
WIRE 17 -1 (-3175 2325)(-3175 2375);
WIRE 17 -1 (-3175 2225)(-3175 2275);
WIRE 17 -1 (-3175 2175)(-3175 2225);
WIRE 17 -1 (-3175 2425)(-3175 2375);
WIRE 17 -1 (-3175 2425)(-3175 2450);
WIRE 17 -1 (-3175 2125)(-3175 2175);
WIRE 17 -1 (-3175 2075)(-3175 2125);
WIRE 17 -1 (-3175 2450)(-2675 2450);
FORCEPROP 2 LAST SIG_NAME M_L_CPU0_SA_CB<7:0>
J 2
(-2675 2460);
DISPLAY 0.489362 (-2675 2460);
WIRE 17 -1 (-3175 1975)(-3175 1925);
WIRE 17 -1 (-3175 1975)(-3175 2000);
WIRE 17 -1 (-3175 1875)(-3175 1925);
WIRE 17 -1 (-3175 1875)(-3175 1825);
WIRE 17 -1 (-3175 2000)(-2675 2000);
FORCEPROP 2 LAST SIG_NAME M_L_CPU0_SB_CB<7:0>
J 2
(-2675 2010);
DISPLAY 0.489362 (-2675 2010);
WIRE 17 -1 (-3175 1775)(-3175 1825);
WIRE 17 -1 (-3175 1725)(-3175 1775);
WIRE 17 -1 (-3175 1675)(-3175 1725);
WIRE 17 -1 (-3175 1625)(-3175 1675);
WIRE 17 -1 (-5700 6025)(-5700 5925);
WIRE 17 -1 (-5700 6025)(-6500 6025);
FORCEPROP 2 LAST SIG_NAME M_L_CPU0_SA_DQS_DP<9:0>
J 2
(-5935 6035);
DISPLAY 0.489362 (-5935 6035);
WIRE 17 -1 (-5700 5925)(-5700 5825);
WIRE 17 -1 (-5700 5825)(-5700 5725);
WIRE 17 -1 (-5700 5725)(-5700 5625);
WIRE 17 -1 (-5700 5525)(-5700 5625);
WIRE 17 -1 (-5700 5425)(-5700 5525);
WIRE 17 -1 (-5700 5325)(-5700 5425);
WIRE 17 -1 (-5700 5325)(-5700 5225);
WIRE 17 -1 (-5700 5225)(-5700 5125);
WIRE 17 -1 (-5900 5975)(-5900 5875);
FORCEPROP 2 LAST SIG_NAME M_L_CPU0_SA_DQS_DN<9:0>
J 2
(-5935 5985);
DISPLAY 0.489362 (-5935 5985);
WIRE 17 -1 (-5900 5775)(-5900 5675);
WIRE 17 -1 (-5900 5875)(-5900 5775);
WIRE 17 -1 (-5900 5675)(-5900 5575);
WIRE 17 -1 (-5900 5475)(-5900 5575);
WIRE 17 -1 (-5900 5375)(-5900 5475);
WIRE 17 -1 (-5900 5275)(-5900 5375);
WIRE 17 -1 (-5900 5275)(-5900 5175);
WIRE 17 -1 (-5900 5175)(-5900 5075);
WIRE 17 -1 (-5700 4975)(-5700 4875);
WIRE 17 -1 (-5700 4975)(-6500 4975);
FORCEPROP 2 LAST SIG_NAME M_L_CPU0_SB_DQS_DP<9:0>
J 2
(-5935 4985);
DISPLAY 0.489362 (-5935 4985);
WIRE 17 -1 (-5700 4875)(-5700 4775);
WIRE 17 -1 (-5700 4775)(-5700 4675);
WIRE 17 -1 (-5700 4675)(-5700 4575);
WIRE 17 -1 (-5700 4475)(-5700 4575);
WIRE 17 -1 (-5700 4375)(-5700 4475);
WIRE 17 -1 (-5700 4275)(-5700 4375);
WIRE 17 -1 (-5700 4275)(-5700 4175);
WIRE 17 -1 (-5700 4175)(-5700 4075);
WIRE 17 -1 (-5900 4925)(-5900 4825);
FORCEPROP 2 LAST SIG_NAME M_L_CPU0_SB_DQS_DN<9:0>
J 2
(-5935 4935);
DISPLAY 0.489362 (-5935 4935);
WIRE 17 -1 (-5900 4725)(-5900 4625);
WIRE 17 -1 (-5900 4825)(-5900 4725);
WIRE 17 -1 (-5900 4625)(-5900 4525);
WIRE 17 -1 (-5900 4425)(-5900 4525);
WIRE 17 -1 (-5900 4325)(-5900 4425);
WIRE 17 -1 (-5900 4225)(-5900 4325);
WIRE 17 -1 (-5900 4225)(-5900 4125);
WIRE 17 -1 (-5900 4125)(-5900 4025);
WIRE 17 -1 (-5900 3425)(-5900 3475);
WIRE 17 -1 (-5900 3375)(-5900 3425);
WIRE 17 -1 (-5900 3475)(-6400 3475);
FORCEPROP 2 LAST SIG_NAME M_L_CPU0_SB_CA<6:0>
J 0
(-6400 3485);
DISPLAY 0.489362 (-6400 3485);
WIRE 17 -1 (-5900 3775)(-5900 3825);
WIRE 17 -1 (-5900 3725)(-5900 3775);
WIRE 17 -1 (-5900 3825)(-5900 3875);
WIRE 17 -1 (-5900 3875)(-6400 3875);
FORCEPROP 2 LAST SIG_NAME M_L_CPU0_SA_CA<6:0>
J 0
(-6400 3885);
DISPLAY 0.489362 (-6400 3885);
WIRE 17 -1 (-5900 3325)(-5900 3375);
WIRE 17 -1 (-5900 3275)(-5900 3325);
WIRE 17 -1 (-5900 3225)(-5900 3275);
WIRE 17 -1 (-5900 3175)(-5900 3225);
WIRE 17 -1 (-5900 3675)(-5900 3725);
WIRE 17 -1 (-5900 3625)(-5900 3675);
WIRE 17 -1 (-5900 3575)(-5900 3625);
WIRE 17 -1 (-5900 5975)(-6500 5975);
WIRE 17 -1 (-5900 4925)(-6500 4925);
WIRE 16 -1 (-7600 2150)(-6875 2150);
FORCEPROP 2 LAST SIG_NAME M_L_CPU0_ALERT_N
J 0
(-7560 2160);
DISPLAY 0.489362 (-7560 2160);
WIRE 16 -1 (-6400 1200)(-5300 1200);
FORCEPROP 2 LAST SIG_NAME TP_M_L_CPU0_SA_TEST39L
J 0
(-6385 1210);
DISPLAY 0.489362 (-6385 1210);
FORCEPROP 2 LASTPROP $XRERR UNIQUE?
J 0
(-6640 1200);
DISPLAY 0.638298 (-6640 1200);
PAINT MONO (-6640 1200);
DISPLAY INVISIBLE (-6640 1200);
WIRE 16 -1 (-6675 2150)(-5300 2150);
FORCEPROP 2 LAST SIG_NAME M_L_CPU0_ALERT_R_N
J 0
(-6385 2160);
DISPLAY 0.489362 (-6385 2160);
FORCEPROP 2 LASTPROP $XRERR UNIQUE?
J 0
(-6625 2160);
DISPLAY 0.638298 (-6625 2160);
PAINT MONO (-6625 2160);
DISPLAY INVISIBLE (-6625 2160);
WIRE 16 -1 (-6400 3000)(-5300 3000);
FORCEPROP 2 LAST SIG_NAME M_L_CPU0_CLK_DP<0>
J 0
(-6400 3010);
DISPLAY 0.489362 (-6400 3010);
WIRE 16 -1 (-6400 2950)(-5300 2950);
FORCEPROP 2 LAST SIG_NAME M_L_CPU0_CLK_DN<0>
J 0
(-6400 2960);
DISPLAY 0.489362 (-6400 2960);
WIRE 16 -1 (-6400 2850)(-5300 2850);
FORCEPROP 2 LAST SIG_NAME M_L_CPU0_SA_CS_N<0>
J 0
(-6400 2860);
DISPLAY 0.489362 (-6400 2860);
WIRE 16 -1 (-6400 2600)(-5300 2600);
FORCEPROP 2 LAST SIG_NAME M_L_CPU0_SA_PAR
J 0
(-6400 2610);
DISPLAY 0.489362 (-6400 2610);
WIRE 16 -1 (-6400 2700)(-5300 2700);
FORCEPROP 2 LAST SIG_NAME M_L_CPU0_SA_RSP<0>
J 0
(-6400 2710);
DISPLAY 0.489362 (-6400 2710);
WIRE 16 -1 (-6400 2800)(-5300 2800);
FORCEPROP 2 LAST SIG_NAME M_L_CPU0_SA_CS_N<1>
J 0
(-6400 2810);
DISPLAY 0.489362 (-6400 2810);
WIRE 16 -1 (-6400 2500)(-5300 2500);
FORCEPROP 2 LAST SIG_NAME M_L_CPU0_SB_CS_N<0>
J 0
(-6400 2510);
DISPLAY 0.489362 (-6400 2510);
WIRE 16 -1 (-6400 2450)(-5300 2450);
FORCEPROP 2 LAST SIG_NAME M_L_CPU0_SB_CS_N<1>
J 0
(-6400 2460);
DISPLAY 0.489362 (-6400 2460);
WIRE 16 -1 (-6400 2350)(-5300 2350);
FORCEPROP 2 LAST SIG_NAME M_L_CPU0_SB_RSP<0>
J 0
(-6400 2360);
DISPLAY 0.489362 (-6400 2360);
WIRE 16 -1 (-6400 2250)(-5300 2250);
FORCEPROP 2 LAST SIG_NAME M_L_CPU0_SB_PAR
J 0
(-6400 2260);
DISPLAY 0.489362 (-6400 2260);
WIRE 16 -1 (-6400 2050)(-5300 2050);
FORCEPROP 2 LAST SIG_NAME M_L_CPU0_RESET_N
J 0
(-6400 2060);
DISPLAY 0.489362 (-6400 2060);
WIRE 16 -1 (-5800 3800)(-5300 3800);
WIRE 16 -1 (-5800 3450)(-5300 3450);
WIRE 16 -1 (-5800 3850)(-5300 3850);
WIRE 16 -1 (-5800 3150)(-5300 3150);
WIRE 16 -1 (-5800 3550)(-5300 3550);
WIRE 16 -1 (-5800 3200)(-5300 3200);
WIRE 16 -1 (-5800 3600)(-5300 3600);
WIRE 16 -1 (-5800 3250)(-5300 3250);
WIRE 16 -1 (-5800 3650)(-5300 3650);
WIRE 16 -1 (-5800 3300)(-5300 3300);
WIRE 16 -1 (-5800 3700)(-5300 3700);
WIRE 16 -1 (-5800 3350)(-5300 3350);
WIRE 16 -1 (-5800 3750)(-5300 3750);
WIRE 16 -1 (-5800 3400)(-5300 3400);
WIRE 16 -1 (-5800 4000)(-5300 4000);
WIRE 16 -1 (-5600 4050)(-5300 4050);
WIRE 16 -1 (-5800 4100)(-5300 4100);
WIRE 16 -1 (-5800 4200)(-5300 4200);
WIRE 16 -1 (-5800 4300)(-5300 4300);
WIRE 16 -1 (-5800 4400)(-5300 4400);
WIRE 16 -1 (-5800 4500)(-5300 4500);
WIRE 16 -1 (-5800 5050)(-5300 5050);
WIRE 16 -1 (-5800 4600)(-5300 4600);
WIRE 16 -1 (-5800 4700)(-5300 4700);
WIRE 16 -1 (-5800 4800)(-5300 4800);
WIRE 16 -1 (-5800 4900)(-5300 4900);
WIRE 16 -1 (-5600 4550)(-5300 4550);
WIRE 16 -1 (-5600 4150)(-5300 4150);
WIRE 16 -1 (-5600 4250)(-5300 4250);
WIRE 16 -1 (-5600 4350)(-5300 4350);
WIRE 16 -1 (-5600 4450)(-5300 4450);
WIRE 16 -1 (-5600 5100)(-5300 5100);
WIRE 16 -1 (-5600 4650)(-5300 4650);
WIRE 16 -1 (-5600 4750)(-5300 4750);
WIRE 16 -1 (-5600 4850)(-5300 4850);
WIRE 16 -1 (-5600 4950)(-5300 4950);
WIRE 16 -1 (-5800 5150)(-5300 5150);
WIRE 16 -1 (-5800 5250)(-5300 5250);
WIRE 16 -1 (-5800 5350)(-5300 5350);
WIRE 16 -1 (-5800 5450)(-5300 5450);
WIRE 16 -1 (-5800 5550)(-5300 5550);
WIRE 16 -1 (-5800 5650)(-5300 5650);
WIRE 16 -1 (-5800 5750)(-5300 5750);
WIRE 16 -1 (-5800 5850)(-5300 5850);
WIRE 16 -1 (-5800 5950)(-5300 5950);
WIRE 16 -1 (-5600 5200)(-5300 5200);
WIRE 16 -1 (-5600 5300)(-5300 5300);
WIRE 16 -1 (-5600 5400)(-5300 5400);
WIRE 16 -1 (-5600 5500)(-5300 5500);
WIRE 16 -1 (-5600 5600)(-5300 5600);
WIRE 16 -1 (-5600 5700)(-5300 5700);
WIRE 16 -1 (-5600 5800)(-5300 5800);
WIRE 16 -1 (-5600 5900)(-5300 5900);
WIRE 16 -1 (-5600 6000)(-5300 6000);
WIRE 16 -1 (-3700 1600)(-3275 1600);
WIRE 16 -1 (-3700 1650)(-3275 1650);
WIRE 16 -1 (-3700 1700)(-3275 1700);
WIRE 16 -1 (-3700 1750)(-3275 1750);
WIRE 16 -1 (-3700 1800)(-3275 1800);
WIRE 16 -1 (-3700 1850)(-3275 1850);
WIRE 16 -1 (-3700 1900)(-3275 1900);
WIRE 16 -1 (-3700 1950)(-3275 1950);
WIRE 16 -1 (-3700 2350)(-3275 2350);
WIRE 16 -1 (-3700 2400)(-3275 2400);
WIRE 16 -1 (-3700 2600)(-3275 2600);
WIRE 16 -1 (-3700 2650)(-3275 2650);
WIRE 16 -1 (-3700 2700)(-3275 2700);
WIRE 16 -1 (-3700 2750)(-3275 2750);
WIRE 16 -1 (-3700 2800)(-3275 2800);
WIRE 16 -1 (-3700 2850)(-3275 2850);
WIRE 16 -1 (-3700 2950)(-3275 2950);
WIRE 16 -1 (-3700 3000)(-3275 3000);
WIRE 16 -1 (-3700 2050)(-3275 2050);
WIRE 16 -1 (-3700 3050)(-3275 3050);
WIRE 16 -1 (-3700 2100)(-3275 2100);
WIRE 16 -1 (-3700 2500)(-3275 2500);
WIRE 16 -1 (-3700 2150)(-3275 2150);
WIRE 16 -1 (-3700 2550)(-3275 2550);
WIRE 16 -1 (-3700 2200)(-3275 2200);
WIRE 16 -1 (-3700 2250)(-3275 2250);
WIRE 16 -1 (-3700 2300)(-3275 2300);
WIRE 16 -1 (-3700 4050)(-3275 4050);
WIRE 16 -1 (-3700 3150)(-3275 3150);
WIRE 16 -1 (-3700 3200)(-3275 3200);
WIRE 16 -1 (-3700 3250)(-3275 3250);
WIRE 16 -1 (-3700 3300)(-3275 3300);
WIRE 16 -1 (-3700 3400)(-3275 3400);
WIRE 16 -1 (-3700 3450)(-3275 3450);
WIRE 16 -1 (-3700 3500)(-3275 3500);
WIRE 16 -1 (-3700 3550)(-3275 3550);
WIRE 16 -1 (-3700 3600)(-3275 3600);
WIRE 16 -1 (-3700 3700)(-3275 3700);
WIRE 16 -1 (-3700 3650)(-3275 3650);
WIRE 16 -1 (-3700 3750)(-3275 3750);
WIRE 16 -1 (-3700 3100)(-3275 3100);
WIRE 16 -1 (-3700 3850)(-3275 3850);
WIRE 16 -1 (-3700 3900)(-3275 3900);
WIRE 16 -1 (-3700 3950)(-3275 3950);
WIRE 16 -1 (-3700 4000)(-3275 4000);
WIRE 16 -1 (-3700 4850)(-3275 4850);
WIRE 16 -1 (-3700 4900)(-3275 4900);
WIRE 16 -1 (-3700 4300)(-3275 4300);
WIRE 16 -1 (-3700 4100)(-3275 4100);
WIRE 16 -1 (-3700 4350)(-3275 4350);
WIRE 16 -1 (-3700 4150)(-3275 4150);
WIRE 16 -1 (-3700 4200)(-3275 4200);
WIRE 16 -1 (-3700 4950)(-3275 4950);
WIRE 16 -1 (-3700 5000)(-3275 5000);
WIRE 16 -1 (-3700 4400)(-3275 4400);
WIRE 16 -1 (-3700 5050)(-3275 5050);
WIRE 16 -1 (-3700 4450)(-3275 4450);
WIRE 16 -1 (-3700 5100)(-3275 5100);
WIRE 16 -1 (-3700 4500)(-3275 4500);
WIRE 16 -1 (-3700 4550)(-3275 4550);
WIRE 16 -1 (-3700 4600)(-3275 4600);
WIRE 16 -1 (-3700 4650)(-3275 4650);
WIRE 16 -1 (-3700 4750)(-3275 4750);
WIRE 16 -1 (-3700 4800)(-3275 4800);
WIRE 16 -1 (-3700 5800)(-3275 5800);
WIRE 16 -1 (-3700 5450)(-3275 5450);
WIRE 16 -1 (-3700 5850)(-3275 5850);
WIRE 16 -1 (-3700 5900)(-3275 5900);
WIRE 16 -1 (-3700 5950)(-3275 5950);
WIRE 16 -1 (-3700 6000)(-3275 6000);
WIRE 16 -1 (-3700 5500)(-3275 5500);
WIRE 16 -1 (-3700 5200)(-3275 5200);
WIRE 16 -1 (-3700 5550)(-3275 5550);
WIRE 16 -1 (-3700 5250)(-3275 5250);
WIRE 16 -1 (-3700 5650)(-3275 5650);
WIRE 16 -1 (-3700 5300)(-3275 5300);
WIRE 16 -1 (-3700 5700)(-3275 5700);
WIRE 16 -1 (-3700 5350)(-3275 5350);
WIRE 16 -1 (-3700 5750)(-3275 5750);
WIRE 16 -1 (-3700 5400)(-3275 5400);
QUIT
